FILE_TYPE = MACRO_DRAWING;
SET COLOR_WIRE YELLOW;
SET COLOR_PROP ORANGE;
SET COLOR_DOT WHITE;
SET COLOR_ARC YELLOW;
SET COLOR_BODY GREEN;
SET COLOR_NOTE PURPLE;
SET PROP_DISPLAY VALUE;
SET PAGE_NUMBER P358;
FORCEADD GL852GOHY60..1
(125 3825);
FORCEPROP 1 LAST LOCATION U268
J 0
(-195 4719);
DISPLAY 0.723404 (-195 4719);
PAINT GREEN (-195 4719);
FORCEPROP 0 LAST $SEC 1
J 0
(-175 4875);
DISPLAY 0.680851 (-175 4875);
PAINT MONO (-175 4875);
DISPLAY INVISIBLE (-175 4875);
FORCEPROP 0 LAST CDS_SEC 1
J 0
(-175 4875);
DISPLAY 1.021277 (-175 4875);
DISPLAY INVISIBLE (-175 4875);
FORCEPROP 0 LASTPIN (-350 4125) $PN 5
J 2
(-360 4135);
DISPLAY 0.680851 (-360 4135);
PAINT MONO (-360 4135);
FORCEPROP 0 LASTPIN (-350 4075) $PN 9
J 2
(-360 4085);
DISPLAY 0.680851 (-360 4085);
PAINT MONO (-360 4085);
FORCEPROP 0 LASTPIN (-350 4025) $PN 14
J 2
(-360 4035);
DISPLAY 0.680851 (-360 4035);
PAINT MONO (-360 4035);
FORCEPROP 0 LASTPIN (600 3875) $PN 1
J 0
(610 3885);
DISPLAY 0.680851 (610 3885);
PAINT MONO (610 3885);
FORCEPROP 0 LASTPIN (600 3775) $PN 3
J 0
(610 3785);
DISPLAY 0.680851 (610 3785);
PAINT MONO (610 3785);
FORCEPROP 0 LASTPIN (600 3675) $PN 6
J 0
(610 3685);
DISPLAY 0.680851 (610 3685);
PAINT MONO (610 3685);
FORCEPROP 0 LASTPIN (600 3575) $PN 12
J 0
(610 3585);
DISPLAY 0.680851 (610 3585);
PAINT MONO (610 3585);
FORCEPROP 0 LASTPIN (600 3475) $PN 15
J 0
(610 3485);
DISPLAY 0.680851 (610 3485);
PAINT MONO (610 3485);
FORCEPROP 0 LASTPIN (600 3925) $PN 2
J 0
(610 3935);
DISPLAY 0.680851 (610 3935);
PAINT MONO (610 3935);
FORCEPROP 0 LASTPIN (600 3825) $PN 4
J 0
(610 3835);
DISPLAY 0.680851 (610 3835);
PAINT MONO (610 3835);
FORCEPROP 0 LASTPIN (600 3725) $PN 7
J 0
(610 3735);
DISPLAY 0.680851 (610 3735);
PAINT MONO (610 3735);
FORCEPROP 0 LASTPIN (600 3625) $PN 13
J 0
(610 3635);
DISPLAY 0.680851 (610 3635);
PAINT MONO (610 3635);
FORCEPROP 0 LASTPIN (600 3525) $PN 16
J 0
(610 3535);
DISPLAY 0.680851 (610 3535);
PAINT MONO (610 3535);
FORCEPROP 0 LASTPIN (-350 3925) $PN 21
J 2
(-360 3935);
DISPLAY 0.680851 (-360 3935);
PAINT MONO (-360 3935);
FORCEPROP 0 LASTPIN (-350 3775) $PN 25
J 2
(-360 3785);
DISPLAY 0.680851 (-360 3785);
PAINT MONO (-360 3785);
FORCEPROP 0 LASTPIN (-350 3725) $PN 24
J 2
(-360 3735);
DISPLAY 0.680851 (-360 3735);
PAINT MONO (-360 3735);
FORCEPROP 0 LASTPIN (-350 3675) $PN 20
J 2
(-360 3685);
DISPLAY 0.680851 (-360 3685);
PAINT MONO (-360 3685);
FORCEPROP 0 LASTPIN (-350 3625) $PN 19
J 2
(-360 3635);
DISPLAY 0.680851 (-360 3635);
PAINT MONO (-360 3635);
FORCEPROP 0 LASTPIN (-350 3325) $PN 23
J 2
(-360 3335);
DISPLAY 0.680851 (-360 3335);
PAINT MONO (-360 3335);
FORCEPROP 0 LASTPIN (-350 3375) $PN 22
J 2
(-360 3385);
DISPLAY 0.680851 (-360 3385);
PAINT MONO (-360 3385);
FORCEPROP 0 LASTPIN (-350 3425) $PN 17
J 2
(-360 3435);
DISPLAY 0.680851 (-360 3435);
PAINT MONO (-360 3435);
FORCEPROP 0 LASTPIN (-350 3475) $PN 8
J 2
(-360 3485);
DISPLAY 0.680851 (-360 3485);
PAINT MONO (-360 3485);
FORCEPROP 0 LASTPIN (600 4325) $PN 26
J 0
(610 4335);
DISPLAY 0.680851 (610 4335);
PAINT MONO (610 4335);
FORCEPROP 0 LASTPIN (600 4275) $PN 18
J 0
(610 4285);
DISPLAY 0.680851 (610 4285);
PAINT MONO (610 4285);
FORCEPROP 0 LASTPIN (600 3325) $PN TH
J 0
(610 3335);
DISPLAY 0.680851 (610 3335);
PAINT MONO (610 3335);
FORCEPROP 0 LASTPIN (-350 4325) $PN 27
J 2
(-360 4335);
DISPLAY 0.680851 (-360 4335);
PAINT MONO (-360 4335);
FORCEPROP 0 LASTPIN (-350 4225) $PN 28
J 2
(-360 4235);
DISPLAY 0.680851 (-360 4235);
PAINT MONO (-360 4235);
FORCEPROP 0 LASTPIN (600 4125) $PN 10
J 0
(615 4135);
DISPLAY 0.680851 (615 4135);
PAINT MONO (615 4135);
FORCEPROP 0 LASTPIN (600 4075) $PN 11
J 0
(610 4085);
DISPLAY 0.680851 (610 4085);
PAINT MONO (610 4085);
FORCEPROP 2 LAST VALUE GL852G-OHY60
J 0
(-175 4775);
DISPLAY 1.021277 (-175 4775);
FORCEPROP 1 LAST MATERIAL IC
J 0
(-195 4445);
DISPLAY 0.723404 (-195 4445);
PAINT GREEN (-195 4445);
FORCEPROP 2 LAST PART_TYPE SMLF
J 0
(-175 4825);
DISPLAY 1.021277 (-175 4825);
FORCEPROP 2 LAST ROOM USB2 BOM1
J 0
(-175 4875);
DISPLAY 0.680851 (-175 4875);
PAINT RED (-175 4875);
FORCEPROP 2 LAST CDS_LIB pure_quanta
J 0
(125 3825);
DISPLAY INVISIBLE (125 3825);
FORCEPROP 1 LAST CDS_LMAN_SYM_OUTLINE -325,600,325,-600
J 0
(125 3825);
DISPLAY 0.468085 (125 3825);
PAINT GREEN (125 3825);
DISPLAY INVISIBLE (125 3825);
FORCEPROP 1 LAST NEEDS_NO_SIZE TRUE
J 0
(125 3825);
DISPLAY 0.723404 (125 3825);
PAINT GREEN (125 3825);
DISPLAY INVISIBLE (125 3825);
FORCEPROP 1 LAST PATH I100
J 0
(125 3825);
DISPLAY 0.723404 (125 3825);
PAINT GREEN (125 3825);
DISPLAY INVISIBLE (125 3825);
FORCEPROP 1 LAST PART_NUMBER AL000852001
J 0
(-195 4572);
DISPLAY 0.723404 (-195 4572);
PAINT GREEN (-195 4572);
DISPLAY INVISIBLE (-195 4572);
FORCEADD UNIVERSAL_GND..1
(3700 4325);
FORCEPROP 3 LASTPIN (3700 4375) SIG_NAME GND\g
J 0
(3710 4385);
DISPLAY 0.659574 (3710 4385);
PAINT MONO (3710 4385);
DISPLAY INVISIBLE (3710 4385);
FORCEPROP 2 LAST CDS_LIB pure_quanta_power
J 0
(3700 4325);
DISPLAY INVISIBLE (3700 4325);
FORCEPROP 1 LAST HDL_POWER GND
J 1
(3725 4250);
DISPLAY 0.872340 (3725 4250);
PAINT GREEN (3725 4250);
DISPLAY INVISIBLE (3725 4250);
FORCEPROP 1 LAST PATH I115
J 0
(3775 4325);
DISPLAY 0.872340 (3775 4325);
PAINT AQUA (3775 4325);
DISPLAY INVISIBLE (3775 4325);
FORCEADD UNIVERSAL_GND..1
(4350 4325);
FORCEPROP 3 LASTPIN (4350 4375) SIG_NAME GND\g
J 0
(4360 4385);
DISPLAY 0.659574 (4360 4385);
PAINT MONO (4360 4385);
DISPLAY INVISIBLE (4360 4385);
FORCEPROP 2 LAST CDS_LIB pure_quanta_power
J 0
(4350 4325);
DISPLAY INVISIBLE (4350 4325);
FORCEPROP 1 LAST HDL_POWER GND
J 1
(4375 4250);
DISPLAY 0.872340 (4375 4250);
PAINT GREEN (4375 4250);
DISPLAY INVISIBLE (4375 4250);
FORCEPROP 1 LAST PATH I116
J 0
(4425 4325);
DISPLAY 0.872340 (4425 4325);
PAINT AQUA (4425 4325);
DISPLAY INVISIBLE (4425 4325);
FORCEADD UNIVERSAL_GND..1
(4475 4150);
FORCEPROP 3 LASTPIN (4475 4200) SIG_NAME GND\g
J 0
(4485 4210);
DISPLAY 0.659574 (4485 4210);
PAINT MONO (4485 4210);
DISPLAY INVISIBLE (4485 4210);
FORCEPROP 2 LAST CDS_LIB pure_quanta_power
J 0
(4475 4150);
DISPLAY INVISIBLE (4475 4150);
FORCEPROP 1 LAST HDL_POWER GND
J 1
(4500 4075);
DISPLAY 0.872340 (4500 4075);
PAINT GREEN (4500 4075);
DISPLAY INVISIBLE (4500 4075);
FORCEPROP 1 LAST PATH I117
J 0
(4550 4150);
DISPLAY 0.872340 (4550 4150);
PAINT AQUA (4550 4150);
DISPLAY INVISIBLE (4550 4150);
FORCEADD UNIVERSAL_GND..1
(3475 4150);
FORCEPROP 3 LASTPIN (3475 4200) SIG_NAME GND\g
J 0
(3485 4210);
DISPLAY 0.659574 (3485 4210);
PAINT MONO (3485 4210);
DISPLAY INVISIBLE (3485 4210);
FORCEPROP 2 LAST CDS_LIB pure_quanta_power
J 0
(3475 4150);
DISPLAY INVISIBLE (3475 4150);
FORCEPROP 1 LAST HDL_POWER GND
J 1
(3500 4075);
DISPLAY 0.872340 (3500 4075);
PAINT GREEN (3500 4075);
DISPLAY INVISIBLE (3500 4075);
FORCEPROP 1 LAST PATH I118
J 0
(3550 4150);
DISPLAY 0.872340 (3550 4150);
PAINT AQUA (3550 4150);
DISPLAY INVISIBLE (3550 4150);
FORCEADD UNIVERSAL_GND..1
R 1
(2025 4275);
FORCEPROP 3 LASTPIN (1975 4275) SIG_NAME GND\g
J 0
(1985 4285);
DISPLAY 0.659574 (1985 4285);
PAINT MONO (1985 4285);
DISPLAY INVISIBLE (1985 4285);
FORCEPROP 2 LAST CDS_LIB pure_quanta_power
J 0
(2025 4275);
DISPLAY INVISIBLE (2025 4275);
FORCEPROP 1 LAST HDL_POWER GND
R 1
J 1
(2100 4300);
DISPLAY 0.872340 (2100 4300);
PAINT GREEN (2100 4300);
DISPLAY INVISIBLE (2100 4300);
FORCEPROP 1 LAST PATH I122
R 1
J 0
(2025 4350);
DISPLAY 0.872340 (2025 4350);
PAINT AQUA (2025 4350);
DISPLAY INVISIBLE (2025 4350);
FORCEADD OFFPAGE..6
R 2
(1675 3825);
PAINT AQUA (1675 3825);
FORCEPROP 2 LAST $XR0 235 
J 0
(1889 3825);
DISPLAY 0.638298 (1889 3825);
PAINT MONO (1889 3825);
FORCEPROP 2 LAST CDS_LIB standard
J 2
(1675 3825);
DISPLAY INVISIBLE (1675 3825);
FORCEPROP 1 LAST OFFPAGE TRUE
J 2
(1350 3700);
DISPLAY 0.872340 (1350 3700);
PAINT AQUA (1350 3700);
DISPLAY INVISIBLE (1350 3700);
FORCEPROP 1 LAST COMMENT_BODY TRUE
J 2
(1575 3750);
DISPLAY 1.170213 (1575 3750);
PAINT GREEN (1575 3750);
DISPLAY INVISIBLE (1575 3750);
FORCEPROP 2 LAST PATH I133
J 0
(2000 3875);
DISPLAY 1.021277 (2000 3875);
DISPLAY INVISIBLE (2000 3875);
FORCEADD OFFPAGE..6
R 2
(1675 3775);
PAINT AQUA (1675 3775);
FORCEPROP 2 LAST $XR0 235 
J 0
(1889 3775);
DISPLAY 0.638298 (1889 3775);
PAINT MONO (1889 3775);
FORCEPROP 2 LAST CDS_LIB standard
J 2
(1675 3775);
DISPLAY INVISIBLE (1675 3775);
FORCEPROP 1 LAST OFFPAGE TRUE
J 2
(1350 3650);
DISPLAY 0.872340 (1350 3650);
PAINT AQUA (1350 3650);
DISPLAY INVISIBLE (1350 3650);
FORCEPROP 1 LAST COMMENT_BODY TRUE
J 2
(1575 3700);
DISPLAY 1.170213 (1575 3700);
PAINT GREEN (1575 3700);
DISPLAY INVISIBLE (1575 3700);
FORCEPROP 2 LAST PATH I134
J 0
(2000 3825);
DISPLAY 1.021277 (2000 3825);
DISPLAY INVISIBLE (2000 3825);
FORCEADD OFFPAGE..3
(4200 3925);
PAINT AQUA (4200 3925);
FORCEPROP 2 LAST $XR0 150 
J 0
(4414 3925);
DISPLAY 0.638298 (4414 3925);
PAINT MONO (4414 3925);
FORCEPROP 2 LAST CDS_LIB standard
J 0
(4200 3925);
DISPLAY INVISIBLE (4200 3925);
FORCEPROP 1 LAST OFFPAGE TRUE
J 0
(4525 3800);
DISPLAY 0.872340 (4525 3800);
PAINT AQUA (4525 3800);
DISPLAY INVISIBLE (4525 3800);
FORCEPROP 1 LAST COMMENT_BODY TRUE
J 0
(4150 3825);
DISPLAY 0.872340 (4150 3825);
PAINT GREEN (4150 3825);
DISPLAY INVISIBLE (4150 3825);
FORCEPROP 2 LAST PATH I135
J 0
(4425 3975);
DISPLAY 1.021277 (4425 3975);
DISPLAY INVISIBLE (4425 3975);
FORCEADD OFFPAGE..3
(4200 3875);
PAINT AQUA (4200 3875);
FORCEPROP 2 LAST $XR0 150 
J 0
(4414 3875);
DISPLAY 0.638298 (4414 3875);
PAINT MONO (4414 3875);
FORCEPROP 2 LAST CDS_LIB standard
J 0
(4200 3875);
DISPLAY INVISIBLE (4200 3875);
FORCEPROP 1 LAST OFFPAGE TRUE
J 0
(4525 3750);
DISPLAY 0.872340 (4525 3750);
PAINT AQUA (4525 3750);
DISPLAY INVISIBLE (4525 3750);
FORCEPROP 1 LAST COMMENT_BODY TRUE
J 0
(4150 3775);
DISPLAY 0.872340 (4150 3775);
PAINT GREEN (4150 3775);
DISPLAY INVISIBLE (4150 3775);
FORCEPROP 2 LAST PATH I136
J 0
(4425 3925);
DISPLAY 1.021277 (4425 3925);
DISPLAY INVISIBLE (4425 3925);
FORCEADD Q_RES..1
(2550 3875);
FORCEPROP 1 LAST LOCATION R3652
J 0
(2300 3875);
DISPLAY 0.723404 (2300 3875);
FORCEPROP 2 LAST $SEC 1
J 0
(2500 4075);
DISPLAY 0.680851 (2500 4075);
PAINT MONO (2500 4075);
DISPLAY INVISIBLE (2500 4075);
FORCEPROP 2 LAST CDS_SEC 1
J 0
(2500 4075);
DISPLAY 1.021277 (2500 4075);
DISPLAY INVISIBLE (2500 4075);
FORCEPROP 1 LASTPIN (2450 3875) $PN 1
J 0
(2462 3887);
DISPLAY 0.723404 (2462 3887);
PAINT MONO (2462 3887);
FORCEPROP 1 LASTPIN (2650 3875) $PN 2
J 0
(2612 3887);
DISPLAY 0.723404 (2612 3887);
PAINT MONO (2612 3887);
FORCEPROP 1 LAST MATERIAL CHIP
J 0
(1900 3875);
DISPLAY 0.723404 (1900 3875);
FORCEPROP 1 LAST PACK_TYPE 0402LF
J 0
(2075 3875);
DISPLAY 0.723404 (2075 3875);
FORCEPROP 2 LAST ROOM USB2 BOM1
J 0
(2450 3800);
DISPLAY 0.680851 (2450 3800);
PAINT RED (2450 3800);
FORCEPROP 1 LAST VALUE 0
J 2
(2700 3875);
DISPLAY 0.723404 (2700 3875);
FORCEPROP 1 LAST TOLERANCE 5%
J 0
(2350 3800);
DISPLAY 0.723404 (2350 3800);
PAINT SKYBLUE (2350 3800);
DISPLAY INVISIBLE (2350 3800);
FORCEPROP 1 LAST WATTAGE 1/16W
J 2
(2625 3800);
DISPLAY 0.723404 (2625 3800);
PAINT SKYBLUE (2625 3800);
DISPLAY INVISIBLE (2625 3800);
FORCEPROP 2 LAST CDS_LIB pure_quanta
J 0
(2550 3875);
DISPLAY INVISIBLE (2550 3875);
FORCEPROP 1 LAST PATH I137
J 0
(2500 4025);
DISPLAY 0.978723 (2500 4025);
PAINT WHITE (2500 4025);
DISPLAY INVISIBLE (2500 4025);
FORCEPROP 1 LAST PART_NUMBER CS00002JB13
J 0
(2275 3750);
DISPLAY 0.723404 (2275 3750);
PAINT WHITE (2275 3750);
DISPLAY INVISIBLE (2275 3750);
FORCEADD Q_RES..1
(2550 3925);
FORCEPROP 1 LAST LOCATION R3651
J 0
(2300 3925);
DISPLAY 0.723404 (2300 3925);
FORCEPROP 2 LAST $SEC 1
J 0
(2500 4125);
DISPLAY 0.680851 (2500 4125);
PAINT MONO (2500 4125);
DISPLAY INVISIBLE (2500 4125);
FORCEPROP 2 LAST CDS_SEC 1
J 0
(2500 4125);
DISPLAY 1.021277 (2500 4125);
DISPLAY INVISIBLE (2500 4125);
FORCEPROP 1 LASTPIN (2450 3925) $PN 1
J 0
(2462 3937);
DISPLAY 0.723404 (2462 3937);
PAINT MONO (2462 3937);
FORCEPROP 1 LASTPIN (2650 3925) $PN 2
J 0
(2612 3937);
DISPLAY 0.723404 (2612 3937);
PAINT MONO (2612 3937);
FORCEPROP 1 LAST PACK_TYPE 0402LF
J 0
(2075 3925);
DISPLAY 0.723404 (2075 3925);
FORCEPROP 2 LAST ROOM USB2 BOM1
J 0
(2450 4000);
DISPLAY 0.680851 (2450 4000);
PAINT RED (2450 4000);
FORCEPROP 1 LAST VALUE 0
J 2
(2700 3925);
DISPLAY 0.723404 (2700 3925);
FORCEPROP 1 LAST MATERIAL CHIP
J 0
(1900 3925);
DISPLAY 0.723404 (1900 3925);
FORCEPROP 1 LAST WATTAGE 1/16W
J 2
(2625 3850);
DISPLAY 0.723404 (2625 3850);
PAINT SKYBLUE (2625 3850);
DISPLAY INVISIBLE (2625 3850);
FORCEPROP 1 LAST TOLERANCE 5%
J 0
(2350 3850);
DISPLAY 0.723404 (2350 3850);
PAINT SKYBLUE (2350 3850);
DISPLAY INVISIBLE (2350 3850);
FORCEPROP 2 LAST CDS_LIB pure_quanta
J 0
(2550 3925);
DISPLAY INVISIBLE (2550 3925);
FORCEPROP 1 LAST PATH I138
J 0
(2500 4075);
DISPLAY 0.978723 (2500 4075);
PAINT WHITE (2500 4075);
DISPLAY INVISIBLE (2500 4075);
FORCEPROP 1 LAST PART_NUMBER CS00002JB13
J 0
(2275 3800);
DISPLAY 0.723404 (2275 3800);
PAINT WHITE (2275 3800);
DISPLAY INVISIBLE (2275 3800);
FORCEADD Q_RES..2
(-1075 3100);
FORCEPROP 1 LAST LOCATION R3653
J 0
(-1025 3200);
DISPLAY 0.510638 (-1025 3200);
FORCEPROP 0 LAST $SEC 1
J 0
(-1025 3275);
DISPLAY 0.680851 (-1025 3275);
PAINT MONO (-1025 3275);
DISPLAY INVISIBLE (-1025 3275);
FORCEPROP 0 LAST CDS_SEC 1
J 0
(-1025 3275);
DISPLAY 1.021277 (-1025 3275);
DISPLAY INVISIBLE (-1025 3275);
FORCEPROP 1 LASTPIN (-1075 3200) $PN 1
J 0
(-1070 3162);
DISPLAY 0.787234 (-1070 3162);
PAINT MONO (-1070 3162);
FORCEPROP 1 LASTPIN (-1075 3000) $PN 2
J 0
(-1070 3010);
DISPLAY 0.787234 (-1070 3010);
PAINT MONO (-1070 3010);
FORCEPROP 1 LAST WATTAGE 1/16W
J 0
(-1035 3075);
DISPLAY 0.510638 (-1035 3075);
FORCEPROP 2 LAST ROOM USB2 BOM1
J 0
(-1025 3250);
DISPLAY 0.553191 (-1025 3250);
PAINT RED (-1025 3250);
FORCEPROP 1 LAST PACK_TYPE 0402LF
J 0
(-1035 2925);
DISPLAY 0.510638 (-1035 2925);
FORCEPROP 1 LAST MATERIAL CHIP
J 0
(-1035 3025);
DISPLAY 0.510638 (-1035 3025);
FORCEPROP 1 LAST TOLERANCE 1%
J 0
(-1030 3125);
DISPLAY 0.510638 (-1030 3125);
FORCEPROP 1 LAST VALUE 680
J 0
(-1030 3175);
DISPLAY 0.404255 (-1030 3175);
FORCEPROP 2 LAST CDS_LIB pure_quanta
J 0
(-1075 3100);
DISPLAY INVISIBLE (-1075 3100);
FORCEPROP 1 LAST PATH I139
J 0
(-1025 3275);
DISPLAY 0.978723 (-1025 3275);
PAINT WHITE (-1025 3275);
DISPLAY INVISIBLE (-1025 3275);
FORCEPROP 1 LAST PART_NUMBER CS16802FB03
J 0
(-1035 2975);
DISPLAY 0.510638 (-1035 2975);
DISPLAY INVISIBLE (-1035 2975);
FORCEADD UNIVERSAL_GND..1
(-1075 2825);
FORCEPROP 3 LASTPIN (-1075 2875) SIG_NAME GND\g
J 0
(-1065 2885);
DISPLAY 0.659574 (-1065 2885);
PAINT MONO (-1065 2885);
DISPLAY INVISIBLE (-1065 2885);
FORCEPROP 2 LAST CDS_LIB pure_quanta_power
J 0
(-1075 2825);
DISPLAY INVISIBLE (-1075 2825);
FORCEPROP 1 LAST HDL_POWER GND
J 1
(-1050 2750);
DISPLAY 0.872340 (-1050 2750);
PAINT GREEN (-1050 2750);
DISPLAY INVISIBLE (-1050 2750);
FORCEPROP 1 LAST PATH I140
J 0
(-1000 2825);
DISPLAY 0.872340 (-1000 2825);
PAINT AQUA (-1000 2825);
DISPLAY INVISIBLE (-1000 2825);
FORCEADD Q_CAP..1
R 2
(-1175 4500);
FORCEPROP 1 LAST LOCATION C2034
J 2
(-975 4575);
DISPLAY 0.638298 (-975 4575);
FORCEPROP 0 LAST $SEC 1
J 0
(-1225 4650);
DISPLAY 0.680851 (-1225 4650);
PAINT MONO (-1225 4650);
DISPLAY INVISIBLE (-1225 4650);
FORCEPROP 0 LAST CDS_SEC 1
J 0
(-1225 4650);
DISPLAY 1.021277 (-1225 4650);
DISPLAY INVISIBLE (-1225 4650);
FORCEPROP 1 LASTPIN (-1175 4600) $PN 1
J 2
(-1185 4580);
DISPLAY 0.787234 (-1185 4580);
PAINT MONO (-1185 4580);
FORCEPROP 1 LASTPIN (-1175 4400) $PN 2
J 2
(-1185 4380);
DISPLAY 0.787234 (-1185 4380);
PAINT MONO (-1185 4380);
FORCEPROP 2 LAST ROOM USB2 BOM1
J 0
(-1125 4625);
DISPLAY 0.680851 (-1125 4625);
PAINT RED (-1125 4625);
FORCEPROP 1 LAST VOLTAGE 25V
J 2
(-1025 4475);
DISPLAY 0.510638 (-1025 4475);
FORCEPROP 1 LAST VALUE 0.1UF
J 2
(-975 4525);
DISPLAY 0.510638 (-975 4525);
FORCEPROP 1 LAST MATERIAL X7R
J 2
(-1025 4375);
DISPLAY 0.510638 (-1025 4375);
FORCEPROP 1 LAST TOLERANCE 10%
J 2
(-1025 4425);
DISPLAY 0.510638 (-1025 4425);
FORCEPROP 1 LAST PACK_TYPE 0402
J 2
(-1000 4275);
DISPLAY 0.510638 (-1000 4275);
FORCEPROP 2 LAST CDS_LIB pure_quanta
J 0
(-1175 4500);
DISPLAY INVISIBLE (-1175 4500);
FORCEPROP 1 LAST PATH I142
J 2
(-1225 4650);
DISPLAY 0.978723 (-1225 4650);
PAINT WHITE (-1225 4650);
DISPLAY INVISIBLE (-1225 4650);
FORCEPROP 1 LAST PART_NUMBER CH4104K1B00
J 2
(-825 4325);
DISPLAY 0.510638 (-825 4325);
DISPLAY INVISIBLE (-825 4325);
FORCEADD Q_CAP..1
R 2
(-1550 4500);
FORCEPROP 1 LAST LOCATION C2033
J 2
(-1375 4575);
DISPLAY 0.510638 (-1375 4575);
FORCEPROP 0 LAST $SEC 1
J 0
(-1600 4650);
DISPLAY 0.680851 (-1600 4650);
PAINT MONO (-1600 4650);
DISPLAY INVISIBLE (-1600 4650);
FORCEPROP 0 LAST CDS_SEC 1
J 0
(-1600 4650);
DISPLAY 1.021277 (-1600 4650);
DISPLAY INVISIBLE (-1600 4650);
FORCEPROP 1 LASTPIN (-1550 4600) $PN 1
J 2
(-1560 4580);
DISPLAY 0.787234 (-1560 4580);
PAINT MONO (-1560 4580);
FORCEPROP 1 LASTPIN (-1550 4400) $PN 2
J 2
(-1560 4380);
DISPLAY 0.787234 (-1560 4380);
PAINT MONO (-1560 4380);
FORCEPROP 2 LAST ROOM USB2 BOM1
J 0
(-1525 4625);
DISPLAY 0.680851 (-1525 4625);
PAINT RED (-1525 4625);
FORCEPROP 1 LAST PACK_TYPE 0402
J 2
(-1375 4275);
DISPLAY 0.510638 (-1375 4275);
FORCEPROP 1 LAST VALUE 0.1UF
J 2
(-1350 4525);
DISPLAY 0.510638 (-1350 4525);
FORCEPROP 1 LAST TOLERANCE 10%
J 2
(-1400 4425);
DISPLAY 0.510638 (-1400 4425);
FORCEPROP 1 LAST MATERIAL X7R
J 2
(-1400 4375);
DISPLAY 0.510638 (-1400 4375);
FORCEPROP 1 LAST VOLTAGE 25V
J 2
(-1400 4475);
DISPLAY 0.510638 (-1400 4475);
FORCEPROP 2 LAST CDS_LIB pure_quanta
J 0
(-1550 4500);
DISPLAY INVISIBLE (-1550 4500);
FORCEPROP 1 LAST PATH I143
J 2
(-1600 4650);
DISPLAY 0.978723 (-1600 4650);
PAINT WHITE (-1600 4650);
DISPLAY INVISIBLE (-1600 4650);
FORCEPROP 1 LAST PART_NUMBER CH4104K1B00
J 2
(-1200 4325);
DISPLAY 0.510638 (-1200 4325);
DISPLAY INVISIBLE (-1200 4325);
FORCEADD UNIVERSAL_POWER..1
R 2
(-4000 4950);
FORCEPROP 3 LASTPIN (-4000 4900) SIG_NAME P3V3_AUX\g
J 0
(-3990 4910);
DISPLAY 0.659574 (-3990 4910);
PAINT MONO (-3990 4910);
DISPLAY INVISIBLE (-3990 4910);
FORCEPROP 1 LAST HDL_POWER P3V3_AUX
J 1
(-4000 5000);
DISPLAY 0.723404 (-4000 5000);
PAINT GREEN (-4000 5000);
FORCEPROP 2 LAST CDS_LIB pure_quanta_power
J 0
(-4000 4950);
DISPLAY INVISIBLE (-4000 4950);
FORCEPROP 1 LAST PATH I144
J 2
(-4050 4975);
DISPLAY 0.872340 (-4050 4975);
PAINT AQUA (-4050 4975);
DISPLAY INVISIBLE (-4050 4975);
FORCEADD Q_CAP..1
R 2
(-1925 4500);
FORCEPROP 1 LAST LOCATION C2032
J 2
(-1750 4575);
DISPLAY 0.510638 (-1750 4575);
FORCEPROP 0 LAST $SEC 1
J 0
(-1975 4650);
DISPLAY 0.680851 (-1975 4650);
PAINT MONO (-1975 4650);
DISPLAY INVISIBLE (-1975 4650);
FORCEPROP 0 LAST CDS_SEC 1
J 0
(-1975 4650);
DISPLAY 1.021277 (-1975 4650);
DISPLAY INVISIBLE (-1975 4650);
FORCEPROP 1 LASTPIN (-1925 4600) $PN 1
J 2
(-1935 4580);
DISPLAY 0.787234 (-1935 4580);
PAINT MONO (-1935 4580);
FORCEPROP 1 LASTPIN (-1925 4400) $PN 2
J 2
(-1935 4380);
DISPLAY 0.787234 (-1935 4380);
PAINT MONO (-1935 4380);
FORCEPROP 2 LAST ROOM USB2 BOM1
J 0
(-1875 4625);
DISPLAY 0.680851 (-1875 4625);
PAINT RED (-1875 4625);
FORCEPROP 1 LAST PACK_TYPE 0402
J 2
(-1750 4275);
DISPLAY 0.510638 (-1750 4275);
FORCEPROP 1 LAST MATERIAL X7R
J 2
(-1775 4375);
DISPLAY 0.510638 (-1775 4375);
FORCEPROP 1 LAST TOLERANCE 10%
J 2
(-1775 4425);
DISPLAY 0.510638 (-1775 4425);
FORCEPROP 1 LAST VOLTAGE 25V
J 2
(-1775 4475);
DISPLAY 0.510638 (-1775 4475);
FORCEPROP 1 LAST VALUE 0.1UF
J 2
(-1725 4525);
DISPLAY 0.510638 (-1725 4525);
FORCEPROP 2 LAST CDS_LIB pure_quanta
J 0
(-1925 4500);
DISPLAY INVISIBLE (-1925 4500);
FORCEPROP 1 LAST PATH I145
J 2
(-1975 4650);
DISPLAY 0.978723 (-1975 4650);
PAINT WHITE (-1975 4650);
DISPLAY INVISIBLE (-1975 4650);
FORCEPROP 1 LAST PART_NUMBER CH4104K1B00
J 2
(-1575 4325);
DISPLAY 0.510638 (-1575 4325);
DISPLAY INVISIBLE (-1575 4325);
FORCEADD Q_CAP..1
(-825 4500);
FORCEPROP 1 LAST LOCATION C2035
J 0
(-775 4600);
DISPLAY 0.638298 (-775 4600);
FORCEPROP 0 LAST $SEC 1
J 0
(-775 4650);
DISPLAY 0.680851 (-775 4650);
PAINT MONO (-775 4650);
DISPLAY INVISIBLE (-775 4650);
FORCEPROP 0 LAST CDS_SEC 1
J 0
(-775 4650);
DISPLAY 1.021277 (-775 4650);
DISPLAY INVISIBLE (-775 4650);
FORCEPROP 1 LASTPIN (-825 4600) $PN 1
J 0
(-815 4580);
DISPLAY 0.787234 (-815 4580);
PAINT MONO (-815 4580);
FORCEPROP 1 LASTPIN (-825 4400) $PN 2
J 0
(-815 4380);
DISPLAY 0.787234 (-815 4380);
PAINT MONO (-815 4380);
FORCEPROP 2 LAST ROOM USB2 BOM1
J 0
(-775 4650);
DISPLAY 0.680851 (-775 4650);
PAINT RED (-775 4650);
FORCEPROP 1 LAST VALUE 1UF
J 0
(-775 4550);
DISPLAY 0.468085 (-775 4550);
FORCEPROP 1 LAST MATERIAL X6S
J 0
(-775 4400);
DISPLAY 0.468085 (-775 4400);
FORCEPROP 1 LAST VOLTAGE 25V
J 0
(-775 4500);
DISPLAY 0.468085 (-775 4500);
FORCEPROP 1 LAST TOLERANCE 10%
J 0
(-775 4450);
DISPLAY 0.468085 (-775 4450);
FORCEPROP 1 LAST PACK_TYPE C0402
J 0
(-775 4300);
DISPLAY 0.468085 (-775 4300);
FORCEPROP 2 LAST CDS_LIB pure_quanta
J 0
(-825 4500);
DISPLAY INVISIBLE (-825 4500);
FORCEPROP 1 LAST PATH I147
J 0
(-775 4650);
DISPLAY 0.978723 (-775 4650);
PAINT WHITE (-775 4650);
DISPLAY INVISIBLE (-775 4650);
FORCEPROP 1 LAST PART_NUMBER CH5104KEB02
J 0
(-775 4350);
DISPLAY 0.468085 (-775 4350);
DISPLAY INVISIBLE (-775 4350);
FORCEADD Q_CAP..1
(-2300 4500);
FORCEPROP 1 LAST LOCATION C2031
J 0
(-2250 4600);
DISPLAY 0.510638 (-2250 4600);
FORCEPROP 0 LAST $SEC 1
J 0
(-2250 4650);
DISPLAY 0.680851 (-2250 4650);
PAINT MONO (-2250 4650);
DISPLAY INVISIBLE (-2250 4650);
FORCEPROP 0 LAST CDS_SEC 1
J 0
(-2250 4650);
DISPLAY 1.021277 (-2250 4650);
DISPLAY INVISIBLE (-2250 4650);
FORCEPROP 1 LASTPIN (-2300 4600) $PN 1
J 0
(-2290 4580);
DISPLAY 0.787234 (-2290 4580);
PAINT MONO (-2290 4580);
FORCEPROP 1 LASTPIN (-2300 4400) $PN 2
J 0
(-2290 4380);
DISPLAY 0.787234 (-2290 4380);
PAINT MONO (-2290 4380);
FORCEPROP 2 LAST ROOM USB2 BOM1
J 0
(-2275 4650);
DISPLAY 0.680851 (-2275 4650);
PAINT RED (-2275 4650);
FORCEPROP 1 LAST TOLERANCE 10%
J 0
(-2250 4450);
DISPLAY 0.574468 (-2250 4450);
FORCEPROP 1 LAST PACK_TYPE C0402
J 0
(-2250 4300);
DISPLAY 0.574468 (-2250 4300);
FORCEPROP 1 LAST VALUE 1UF
J 0
(-2250 4550);
DISPLAY 0.574468 (-2250 4550);
FORCEPROP 1 LAST VOLTAGE 25V
J 0
(-2250 4500);
DISPLAY 0.574468 (-2250 4500);
FORCEPROP 1 LAST MATERIAL X6S
J 0
(-2250 4400);
DISPLAY 0.574468 (-2250 4400);
FORCEPROP 2 LAST CDS_LIB pure_quanta
J 0
(-2300 4500);
DISPLAY INVISIBLE (-2300 4500);
FORCEPROP 1 LAST PATH I148
J 0
(-2250 4650);
DISPLAY 0.978723 (-2250 4650);
PAINT WHITE (-2250 4650);
DISPLAY INVISIBLE (-2250 4650);
FORCEPROP 1 LAST PART_NUMBER CH5104KEB02
J 0
(-2250 4350);
DISPLAY 0.574468 (-2250 4350);
DISPLAY INVISIBLE (-2250 4350);
FORCEADD UNIVERSAL_POWER..1
R 2
(-1900 4075);
FORCEPROP 3 LASTPIN (-1900 4025) SIG_NAME P3V3_AUX\g
J 0
(-1890 4035);
DISPLAY 0.659574 (-1890 4035);
PAINT MONO (-1890 4035);
DISPLAY INVISIBLE (-1890 4035);
FORCEPROP 1 LAST HDL_POWER P3V3_AUX
J 1
(-1900 4125);
DISPLAY 0.723404 (-1900 4125);
PAINT GREEN (-1900 4125);
FORCEPROP 2 LAST CDS_LIB pure_quanta_power
J 0
(-1900 4075);
DISPLAY INVISIBLE (-1900 4075);
FORCEPROP 1 LAST PATH I151
J 2
(-1950 4100);
DISPLAY 0.872340 (-1950 4100);
PAINT AQUA (-1950 4100);
DISPLAY INVISIBLE (-1950 4100);
FORCEADD Q_RES..1
(-2725 3425);
FORCEPROP 1 LAST LOCATION R3654
J 0
(-2975 3425);
DISPLAY 0.723404 (-2975 3425);
FORCEPROP 0 LAST $SEC 1
J 0
(-3025 3500);
DISPLAY INVISIBLE (-3025 3500);
FORCEPROP 0 LAST CDS_SEC 1
J 0
(-3025 3500);
DISPLAY INVISIBLE (-3025 3500);
FORCEPROP 1 LASTPIN (-2825 3425) $PN 1
J 0
(-2813 3437);
DISPLAY 0.787234 (-2813 3437);
PAINT MONO (-2813 3437);
DISPLAY INVISIBLE (-2813 3437);
FORCEPROP 1 LASTPIN (-2625 3425) $PN 2
J 0
(-2663 3437);
DISPLAY 0.787234 (-2663 3437);
PAINT MONO (-2663 3437);
DISPLAY INVISIBLE (-2663 3437);
FORCEPROP 1 LAST VALUE 33.2
J 2
(-2525 3425);
DISPLAY 0.723404 (-2525 3425);
FORCEPROP 1 LAST MATERIAL CHIP
J 0
(-2650 3375);
DISPLAY 0.723404 (-2650 3375);
FORCEPROP 1 LAST TOLERANCE 1%
J 0
(-2975 3375);
DISPLAY 0.723404 (-2975 3375);
FORCEPROP 1 LAST WATTAGE 1/16W
J 2
(-3000 3375);
DISPLAY 0.723404 (-3000 3375);
FORCEPROP 1 LAST PACK_TYPE 0402LF
J 0
(-2875 3375);
DISPLAY 0.723404 (-2875 3375);
FORCEPROP 2 LAST CDS_LIB pure_quanta
J 0
(-2725 3425);
DISPLAY INVISIBLE (-2725 3425);
FORCEPROP 1 LAST PATH I155
J 0
(-2775 3575);
DISPLAY 0.978723 (-2775 3575);
PAINT WHITE (-2775 3575);
DISPLAY INVISIBLE (-2775 3575);
FORCEPROP 1 LAST PART_NUMBER CS03322FB03
J 0
(-2475 3375);
DISPLAY 0.723404 (-2475 3375);
DISPLAY INVISIBLE (-2475 3375);
FORCEADD OFFPAGE..1
(-3525 3425);
PAINT AQUA (-3525 3425);
FORCEPROP 2 LAST $XR2 178 
J 0
(-4017 3425);
DISPLAY 0.638298 (-4017 3425);
PAINT MONO (-4017 3425);
FORCEPROP 2 LAST $XR1 176 
J 0
(-3897 3425);
DISPLAY 0.638298 (-3897 3425);
PAINT MONO (-3897 3425);
FORCEPROP 2 LAST $XR0 246 
J 0
(-3777 3425);
DISPLAY 0.638298 (-3777 3425);
PAINT MONO (-3777 3425);
FORCEPROP 2 LAST CDS_LIB standard
J 0
(-3525 3425);
DISPLAY INVISIBLE (-3525 3425);
FORCEPROP 1 LAST OFFPAGE TRUE
J 0
(-3200 3300);
DISPLAY 0.872340 (-3200 3300);
PAINT AQUA (-3200 3300);
DISPLAY INVISIBLE (-3200 3300);
FORCEPROP 1 LAST COMMENT_BODY TRUE
J 0
(-3400 3325);
DISPLAY 0.872340 (-3400 3325);
PAINT GREEN (-3400 3325);
DISPLAY INVISIBLE (-3400 3325);
FORCEPROP 2 LAST PATH I156
J 0
(-3700 3475);
DISPLAY 1.021277 (-3700 3475);
DISPLAY INVISIBLE (-3700 3475);
FORCEADD UNIVERSAL_GND..1
(-2275 2850);
FORCEPROP 3 LASTPIN (-2275 2900) SIG_NAME GND\g
J 0
(-2265 2910);
DISPLAY 0.659574 (-2265 2910);
PAINT MONO (-2265 2910);
DISPLAY INVISIBLE (-2265 2910);
FORCEPROP 2 LAST CDS_LIB pure_quanta_power
J 0
(-2275 2850);
DISPLAY INVISIBLE (-2275 2850);
FORCEPROP 1 LAST HDL_POWER GND
J 1
(-2250 2775);
DISPLAY 0.872340 (-2250 2775);
PAINT GREEN (-2250 2775);
DISPLAY INVISIBLE (-2250 2775);
FORCEPROP 1 LAST PATH I157
J 0
(-2200 2850);
DISPLAY 0.872340 (-2200 2850);
PAINT AQUA (-2200 2850);
DISPLAY INVISIBLE (-2200 2850);
FORCEADD Q_CAP..1
(-2275 3150);
FORCEPROP 1 LAST LOCATION C2041
J 0
(-2225 3250);
DISPLAY 0.978723 (-2225 3250);
FORCEPROP 0 LAST $SEC 1
J 0
(-2225 3300);
DISPLAY 0.680851 (-2225 3300);
PAINT MONO (-2225 3300);
DISPLAY INVISIBLE (-2225 3300);
FORCEPROP 0 LAST CDS_SEC 1
J 0
(-2225 3300);
DISPLAY 1.021277 (-2225 3300);
DISPLAY INVISIBLE (-2225 3300);
FORCEPROP 1 LASTPIN (-2275 3250) $PN 1
J 0
(-2265 3230);
DISPLAY 0.787234 (-2265 3230);
PAINT MONO (-2265 3230);
FORCEPROP 1 LASTPIN (-2275 3050) $PN 2
J 0
(-2265 3030);
DISPLAY 0.787234 (-2265 3030);
PAINT MONO (-2265 3030);
FORCEPROP 1 LAST VALUE 1UF
J 0
(-2225 3200);
DISPLAY 0.574468 (-2225 3200);
FORCEPROP 1 LAST MATERIAL X6S
J 0
(-2225 3050);
DISPLAY 0.574468 (-2225 3050);
FORCEPROP 1 LAST PACK_TYPE C0402
J 0
(-2225 2950);
DISPLAY 0.574468 (-2225 2950);
FORCEPROP 1 LAST TOLERANCE 10%
J 0
(-2225 3100);
DISPLAY 0.574468 (-2225 3100);
FORCEPROP 1 LAST VOLTAGE 25V
J 0
(-2225 3150);
DISPLAY 0.574468 (-2225 3150);
FORCEPROP 2 LAST CDS_LIB pure_quanta
J 0
(-2275 3150);
DISPLAY INVISIBLE (-2275 3150);
FORCEPROP 1 LAST PATH I158
J 0
(-2225 3300);
DISPLAY 0.978723 (-2225 3300);
PAINT WHITE (-2225 3300);
DISPLAY INVISIBLE (-2225 3300);
FORCEPROP 1 LAST PART_NUMBER CH5104KEB02
J 0
(-2225 3000);
DISPLAY 0.574468 (-2225 3000);
DISPLAY INVISIBLE (-2225 3000);
FORCEADD Q_RES..2
(-1900 3775);
FORCEPROP 1 LAST LOCATION R3660
J 0
(-1855 3900);
DISPLAY 0.638298 (-1855 3900);
FORCEPROP 0 LAST $SEC 1
J 0
(-1850 3950);
DISPLAY 0.680851 (-1850 3950);
PAINT MONO (-1850 3950);
DISPLAY INVISIBLE (-1850 3950);
FORCEPROP 0 LAST CDS_SEC 1
J 0
(-1850 3950);
DISPLAY 1.021277 (-1850 3950);
DISPLAY INVISIBLE (-1850 3950);
FORCEPROP 1 LASTPIN (-1900 3875) $PN 1
J 0
(-1895 3837);
DISPLAY 0.787234 (-1895 3837);
PAINT MONO (-1895 3837);
FORCEPROP 1 LASTPIN (-1900 3675) $PN 2
J 0
(-1895 3685);
DISPLAY 0.787234 (-1895 3685);
PAINT MONO (-1895 3685);
FORCEPROP 1 LAST TOLERANCE 1%
J 0
(-1855 3800);
DISPLAY 0.638298 (-1855 3800);
FORCEPROP 1 LAST WATTAGE 1/16W
J 0
(-1860 3750);
DISPLAY 0.638298 (-1860 3750);
FORCEPROP 1 LAST VALUE 10K
J 0
(-1855 3850);
DISPLAY 0.638298 (-1855 3850);
FORCEPROP 1 LAST PACK_TYPE 0402LF
J 0
(-1860 3600);
DISPLAY 0.638298 (-1860 3600);
FORCEPROP 1 LAST MATERIAL CHIP
J 0
(-1860 3700);
DISPLAY 0.638298 (-1860 3700);
FORCEPROP 2 LAST CDS_LIB pure_quanta
J 0
(-1900 3775);
DISPLAY INVISIBLE (-1900 3775);
FORCEPROP 1 LAST PATH I159
J 0
(-1850 3950);
DISPLAY 0.978723 (-1850 3950);
PAINT WHITE (-1850 3950);
DISPLAY INVISIBLE (-1850 3950);
FORCEPROP 1 LAST PART_NUMBER CS31002FB08
J 0
(-1860 3650);
DISPLAY 0.638298 (-1860 3650);
DISPLAY INVISIBLE (-1860 3650);
FORCEADD Q_RES..1
(-3750 4800);
FORCEPROP 1 LAST LOCATION R3655
J 0
(-3975 4800);
DISPLAY 0.638298 (-3975 4800);
FORCEPROP 0 LAST $SEC 1
J 0
(-3600 4850);
DISPLAY 0.680851 (-3600 4850);
PAINT MONO (-3600 4850);
DISPLAY INVISIBLE (-3600 4850);
FORCEPROP 0 LAST CDS_SEC 1
J 0
(-3600 4850);
DISPLAY 1.021277 (-3600 4850);
DISPLAY INVISIBLE (-3600 4850);
FORCEPROP 1 LASTPIN (-3850 4800) $PN 1
J 0
(-3838 4812);
DISPLAY 0.787234 (-3838 4812);
PAINT MONO (-3838 4812);
FORCEPROP 1 LASTPIN (-3650 4800) $PN 2
J 0
(-3688 4812);
DISPLAY 0.787234 (-3688 4812);
PAINT MONO (-3688 4812);
FORCEPROP 2 LAST ROOM USB2 BOM1
J 0
(-3850 4900);
DISPLAY 0.680851 (-3850 4900);
PAINT RED (-3850 4900);
FORCEPROP 1 LAST PACK_TYPE 0402LF
J 0
(-3750 4725);
DISPLAY 0.723404 (-3750 4725);
FORCEPROP 1 LAST MATERIAL CHIP
J 0
(-3900 4725);
DISPLAY 0.723404 (-3900 4725);
FORCEPROP 1 LAST VALUE 0
J 2
(-3600 4800);
DISPLAY 0.723404 (-3600 4800);
FORCEPROP 2 LAST CDS_LIB pure_quanta
J 0
(-3750 4800);
DISPLAY INVISIBLE (-3750 4800);
FORCEPROP 1 LAST WATTAGE 1/16W
J 2
(-3675 4725);
DISPLAY 0.723404 (-3675 4725);
PAINT SKYBLUE (-3675 4725);
DISPLAY INVISIBLE (-3675 4725);
FORCEPROP 1 LAST TOLERANCE 5%
J 0
(-3950 4725);
DISPLAY 0.723404 (-3950 4725);
PAINT SKYBLUE (-3950 4725);
DISPLAY INVISIBLE (-3950 4725);
FORCEPROP 1 LAST PATH I161
J 0
(-3800 4950);
DISPLAY 0.978723 (-3800 4950);
PAINT WHITE (-3800 4950);
DISPLAY INVISIBLE (-3800 4950);
FORCEPROP 1 LAST PART_NUMBER CS00002JB13
J 0
(-4025 4675);
DISPLAY 0.723404 (-4025 4675);
PAINT WHITE (-4025 4675);
DISPLAY INVISIBLE (-4025 4675);
FORCEADD Q_CAP..1
R 2
(-2675 4500);
FORCEPROP 1 LAST LOCATION C2040
J 2
(-2500 4575);
DISPLAY 0.638298 (-2500 4575);
FORCEPROP 0 LAST $SEC 1
J 0
(-2575 4625);
DISPLAY 0.680851 (-2575 4625);
PAINT MONO (-2575 4625);
DISPLAY INVISIBLE (-2575 4625);
FORCEPROP 0 LAST CDS_SEC 1
J 0
(-2575 4625);
DISPLAY 1.021277 (-2575 4625);
DISPLAY INVISIBLE (-2575 4625);
FORCEPROP 1 LASTPIN (-2675 4600) $PN 1
J 2
(-2685 4580);
DISPLAY 0.787234 (-2685 4580);
PAINT MONO (-2685 4580);
FORCEPROP 1 LASTPIN (-2675 4400) $PN 2
J 2
(-2685 4380);
DISPLAY 0.787234 (-2685 4380);
PAINT MONO (-2685 4380);
FORCEPROP 2 LAST ROOM USB2 BOM1
J 0
(-2600 4625);
DISPLAY 0.680851 (-2600 4625);
PAINT RED (-2600 4625);
FORCEPROP 1 LAST MATERIAL X7R
J 2
(-2525 4375);
DISPLAY 0.510638 (-2525 4375);
FORCEPROP 1 LAST PACK_TYPE 0402
J 2
(-2500 4275);
DISPLAY 0.510638 (-2500 4275);
FORCEPROP 1 LAST TOLERANCE 10%
J 2
(-2525 4425);
DISPLAY 0.510638 (-2525 4425);
FORCEPROP 1 LAST VOLTAGE 25V
J 2
(-2525 4475);
DISPLAY 0.510638 (-2525 4475);
FORCEPROP 1 LAST VALUE 0.1UF
J 2
(-2475 4525);
DISPLAY 0.510638 (-2475 4525);
FORCEPROP 2 LAST CDS_LIB pure_quanta
J 0
(-2675 4500);
DISPLAY INVISIBLE (-2675 4500);
FORCEPROP 1 LAST PATH I162
J 2
(-2725 4650);
DISPLAY 0.978723 (-2725 4650);
PAINT WHITE (-2725 4650);
DISPLAY INVISIBLE (-2725 4650);
FORCEPROP 1 LAST PART_NUMBER CH4104K1B00
J 2
(-2325 4325);
DISPLAY 0.510638 (-2325 4325);
DISPLAY INVISIBLE (-2325 4325);
FORCEADD Q_CAP..1
R 2
(-3075 4500);
FORCEPROP 1 LAST LOCATION C2039
J 2
(-2900 4575);
DISPLAY 0.638298 (-2900 4575);
FORCEPROP 0 LAST $SEC 1
J 0
(-2975 4625);
DISPLAY 0.680851 (-2975 4625);
PAINT MONO (-2975 4625);
DISPLAY INVISIBLE (-2975 4625);
FORCEPROP 0 LAST CDS_SEC 1
J 0
(-2975 4625);
DISPLAY 1.021277 (-2975 4625);
DISPLAY INVISIBLE (-2975 4625);
FORCEPROP 1 LASTPIN (-3075 4600) $PN 1
J 2
(-3085 4580);
DISPLAY 0.787234 (-3085 4580);
PAINT MONO (-3085 4580);
FORCEPROP 1 LASTPIN (-3075 4400) $PN 2
J 2
(-3085 4380);
DISPLAY 0.787234 (-3085 4380);
PAINT MONO (-3085 4380);
FORCEPROP 2 LAST ROOM USB2 BOM1
J 0
(-3000 4625);
DISPLAY 0.680851 (-3000 4625);
PAINT RED (-3000 4625);
FORCEPROP 1 LAST TOLERANCE 10%
J 2
(-2925 4425);
DISPLAY 0.510638 (-2925 4425);
FORCEPROP 1 LAST VOLTAGE 25V
J 2
(-2925 4475);
DISPLAY 0.510638 (-2925 4475);
FORCEPROP 1 LAST MATERIAL X7R
J 2
(-2925 4375);
DISPLAY 0.510638 (-2925 4375);
FORCEPROP 1 LAST PACK_TYPE 0402
J 2
(-2900 4275);
DISPLAY 0.510638 (-2900 4275);
FORCEPROP 1 LAST VALUE 0.1UF
J 2
(-2875 4525);
DISPLAY 0.510638 (-2875 4525);
FORCEPROP 2 LAST CDS_LIB pure_quanta
J 0
(-3075 4500);
DISPLAY INVISIBLE (-3075 4500);
FORCEPROP 1 LAST PATH I163
J 2
(-3125 4650);
DISPLAY 0.978723 (-3125 4650);
PAINT WHITE (-3125 4650);
DISPLAY INVISIBLE (-3125 4650);
FORCEPROP 1 LAST PART_NUMBER CH4104K1B00
J 2
(-2725 4325);
DISPLAY 0.510638 (-2725 4325);
DISPLAY INVISIBLE (-2725 4325);
FORCEADD Q_CAP..1
(-3450 4500);
FORCEPROP 1 LAST LOCATION C2038
J 0
(-3400 4600);
DISPLAY 0.510638 (-3400 4600);
FORCEPROP 0 LAST $SEC 1
J 0
(-3400 4625);
DISPLAY 0.680851 (-3400 4625);
PAINT MONO (-3400 4625);
DISPLAY INVISIBLE (-3400 4625);
FORCEPROP 0 LAST CDS_SEC 1
J 0
(-3400 4625);
DISPLAY 1.021277 (-3400 4625);
DISPLAY INVISIBLE (-3400 4625);
FORCEPROP 1 LASTPIN (-3450 4600) $PN 1
J 0
(-3440 4580);
DISPLAY 0.787234 (-3440 4580);
PAINT MONO (-3440 4580);
FORCEPROP 1 LASTPIN (-3450 4400) $PN 2
J 0
(-3440 4380);
DISPLAY 0.787234 (-3440 4380);
PAINT MONO (-3440 4380);
FORCEPROP 2 LAST ROOM USB2 BOM1
J 0
(-3400 4650);
DISPLAY 0.680851 (-3400 4650);
PAINT RED (-3400 4650);
FORCEPROP 1 LAST TOLERANCE 20%
J 0
(-3400 4450);
DISPLAY 0.510638 (-3400 4450);
FORCEPROP 1 LAST VOLTAGE 6.3V
J 0
(-3400 4500);
DISPLAY 0.510638 (-3400 4500);
FORCEPROP 1 LAST MATERIAL X6S
J 0
(-3400 4400);
DISPLAY 0.510638 (-3400 4400);
FORCEPROP 1 LAST VALUE 10UF
J 0
(-3400 4550);
DISPLAY 0.510638 (-3400 4550);
FORCEPROP 1 LAST PACK_TYPE C0402
J 0
(-3400 4300);
DISPLAY 0.510638 (-3400 4300);
FORCEPROP 2 LAST CDS_LIB pure_quanta
J 0
(-3450 4500);
DISPLAY INVISIBLE (-3450 4500);
FORCEPROP 1 LAST PATH I164
J 0
(-3400 4650);
DISPLAY 0.978723 (-3400 4650);
PAINT WHITE (-3400 4650);
DISPLAY INVISIBLE (-3400 4650);
FORCEPROP 1 LAST PART_NUMBER CH6101MEB01
J 0
(-3400 4350);
DISPLAY 0.510638 (-3400 4350);
DISPLAY INVISIBLE (-3400 4350);
FORCEADD UNIVERSAL_GND..1
(-3450 4100);
FORCEPROP 3 LASTPIN (-3450 4150) SIG_NAME GND\g
J 0
(-3440 4160);
DISPLAY 0.659574 (-3440 4160);
PAINT MONO (-3440 4160);
DISPLAY INVISIBLE (-3440 4160);
FORCEPROP 2 LAST CDS_LIB pure_quanta_power
J 0
(-3450 4100);
DISPLAY INVISIBLE (-3450 4100);
FORCEPROP 1 LAST HDL_POWER GND
J 1
(-3425 4025);
DISPLAY 0.872340 (-3425 4025);
PAINT GREEN (-3425 4025);
DISPLAY INVISIBLE (-3425 4025);
FORCEPROP 1 LAST PATH I165
J 0
(-3375 4100);
DISPLAY 0.872340 (-3375 4100);
PAINT AQUA (-3375 4100);
DISPLAY INVISIBLE (-3375 4100);
FORCEADD UNIVERSAL_GND..1
(725 3125);
FORCEPROP 3 LASTPIN (725 3175) SIG_NAME GND\g
J 0
(735 3185);
DISPLAY 0.659574 (735 3185);
PAINT MONO (735 3185);
DISPLAY INVISIBLE (735 3185);
FORCEPROP 2 LAST CDS_LIB pure_quanta_power
J 0
(725 3125);
DISPLAY INVISIBLE (725 3125);
FORCEPROP 1 LAST HDL_POWER GND
J 1
(750 3050);
DISPLAY 0.872340 (750 3050);
PAINT GREEN (750 3050);
DISPLAY INVISIBLE (750 3050);
FORCEPROP 1 LAST PATH I166
J 0
(800 3125);
DISPLAY 0.872340 (800 3125);
PAINT AQUA (800 3125);
DISPLAY INVISIBLE (800 3125);
FORCEADD Q_RES..1
(-1025 3925);
FORCEPROP 1 LAST LOCATION R3662
J 0
(-1225 3925);
DISPLAY 0.638298 (-1225 3925);
FORCEPROP 0 LAST $SEC 1
J 0
(-875 3975);
DISPLAY 0.680851 (-875 3975);
PAINT MONO (-875 3975);
DISPLAY INVISIBLE (-875 3975);
FORCEPROP 0 LAST CDS_SEC 1
J 0
(-875 3975);
DISPLAY 1.021277 (-875 3975);
DISPLAY INVISIBLE (-875 3975);
FORCEPROP 1 LASTPIN (-1125 3925) $PN 1
J 0
(-1113 3937);
DISPLAY 0.787234 (-1113 3937);
PAINT MONO (-1113 3937);
FORCEPROP 1 LASTPIN (-925 3925) $PN 2
J 0
(-963 3937);
DISPLAY 0.787234 (-963 3937);
PAINT MONO (-963 3937);
FORCEPROP 1 LAST MATERIAL CHIP
J 0
(-1175 3875);
DISPLAY 0.723404 (-1175 3875);
FORCEPROP 1 LAST PACK_TYPE 0402LF
J 0
(-1000 3875);
DISPLAY 0.723404 (-1000 3875);
FORCEPROP 1 LAST VALUE 0
J 2
(-875 3925);
DISPLAY 0.723404 (-875 3925);
FORCEPROP 2 LAST ROOM USB2 BOM1
J 0
(-1175 3975);
DISPLAY 0.680851 (-1175 3975);
PAINT RED (-1175 3975);
FORCEPROP 1 LAST WATTAGE 1/16W
J 2
(-950 3850);
DISPLAY 0.723404 (-950 3850);
PAINT SKYBLUE (-950 3850);
DISPLAY INVISIBLE (-950 3850);
FORCEPROP 1 LAST TOLERANCE 5%
J 0
(-1225 3850);
DISPLAY 0.723404 (-1225 3850);
PAINT SKYBLUE (-1225 3850);
DISPLAY INVISIBLE (-1225 3850);
FORCEPROP 2 LAST CDS_LIB pure_quanta
J 0
(-1025 3925);
DISPLAY INVISIBLE (-1025 3925);
FORCEPROP 1 LAST PATH I167
J 0
(-1075 4075);
DISPLAY 0.978723 (-1075 4075);
PAINT WHITE (-1075 4075);
DISPLAY INVISIBLE (-1075 4075);
FORCEPROP 1 LAST PART_NUMBER CS00002JB13
J 0
(-1300 3800);
DISPLAY 0.723404 (-1300 3800);
PAINT WHITE (-1300 3800);
DISPLAY INVISIBLE (-1300 3800);
FORCEADD OFFPAGE..1
(-975 3775);
PAINT AQUA (-975 3775);
FORCEPROP 2 LAST $XR0 235 
J 0
(-1257 3775);
DISPLAY 0.638298 (-1257 3775);
PAINT MONO (-1257 3775);
FORCEPROP 2 LAST CDS_LIB standard
J 0
(-975 3775);
DISPLAY INVISIBLE (-975 3775);
FORCEPROP 1 LAST OFFPAGE TRUE
J 0
(-650 3650);
DISPLAY 0.872340 (-650 3650);
PAINT AQUA (-650 3650);
DISPLAY INVISIBLE (-650 3650);
FORCEPROP 1 LAST COMMENT_BODY TRUE
J 0
(-850 3675);
DISPLAY 0.872340 (-850 3675);
PAINT GREEN (-850 3675);
DISPLAY INVISIBLE (-850 3675);
FORCEPROP 2 LAST PATH I168
J 0
(-1150 3825);
DISPLAY 1.021277 (-1150 3825);
DISPLAY INVISIBLE (-1150 3825);
FORCEADD OFFPAGE..1
(-975 3725);
PAINT AQUA (-975 3725);
FORCEPROP 2 LAST $XR0 235 
J 0
(-1257 3725);
DISPLAY 0.638298 (-1257 3725);
PAINT MONO (-1257 3725);
FORCEPROP 2 LAST CDS_LIB standard
J 0
(-975 3725);
DISPLAY INVISIBLE (-975 3725);
FORCEPROP 1 LAST OFFPAGE TRUE
J 0
(-650 3600);
DISPLAY 0.872340 (-650 3600);
PAINT AQUA (-650 3600);
DISPLAY INVISIBLE (-650 3600);
FORCEPROP 1 LAST COMMENT_BODY TRUE
J 0
(-850 3625);
DISPLAY 0.872340 (-850 3625);
PAINT GREEN (-850 3625);
DISPLAY INVISIBLE (-850 3625);
FORCEPROP 2 LAST PATH I169
J 0
(-1150 3775);
DISPLAY 1.021277 (-1150 3775);
DISPLAY INVISIBLE (-1150 3775);
FORCEADD OFFPAGE..1
(-975 3675);
PAINT AQUA (-975 3675);
FORCEPROP 2 LAST $XR0 235 
J 0
(-1257 3675);
DISPLAY 0.638298 (-1257 3675);
PAINT MONO (-1257 3675);
FORCEPROP 2 LAST CDS_LIB standard
J 0
(-975 3675);
DISPLAY INVISIBLE (-975 3675);
FORCEPROP 1 LAST OFFPAGE TRUE
J 0
(-650 3550);
DISPLAY 0.872340 (-650 3550);
PAINT AQUA (-650 3550);
DISPLAY INVISIBLE (-650 3550);
FORCEPROP 1 LAST COMMENT_BODY TRUE
J 0
(-850 3575);
DISPLAY 0.872340 (-850 3575);
PAINT GREEN (-850 3575);
DISPLAY INVISIBLE (-850 3575);
FORCEPROP 2 LAST PATH I170
J 0
(-1150 3725);
DISPLAY 1.021277 (-1150 3725);
DISPLAY INVISIBLE (-1150 3725);
FORCEADD OFFPAGE..1
(-975 3625);
PAINT AQUA (-975 3625);
FORCEPROP 2 LAST $XR0 235 
J 0
(-1257 3625);
DISPLAY 0.638298 (-1257 3625);
PAINT MONO (-1257 3625);
FORCEPROP 2 LAST CDS_LIB standard
J 0
(-975 3625);
DISPLAY INVISIBLE (-975 3625);
FORCEPROP 1 LAST OFFPAGE TRUE
J 0
(-650 3500);
DISPLAY 0.872340 (-650 3500);
PAINT AQUA (-650 3500);
DISPLAY INVISIBLE (-650 3500);
FORCEPROP 1 LAST COMMENT_BODY TRUE
J 0
(-850 3525);
DISPLAY 0.872340 (-850 3525);
PAINT GREEN (-850 3525);
DISPLAY INVISIBLE (-850 3525);
FORCEPROP 2 LAST PATH I171
J 0
(-1150 3675);
DISPLAY 1.021277 (-1150 3675);
DISPLAY INVISIBLE (-1150 3675);
FORCEADD Q_RES..2
(-750 3075);
FORCEPROP 1 LAST LOCATION R3665
J 0
(-705 3200);
DISPLAY 0.510638 (-705 3200);
FORCEPROP 0 LAST $SEC 1
J 0
(-700 3250);
DISPLAY 0.680851 (-700 3250);
PAINT MONO (-700 3250);
DISPLAY INVISIBLE (-700 3250);
FORCEPROP 0 LAST CDS_SEC 1
J 0
(-700 3250);
DISPLAY 1.021277 (-700 3250);
DISPLAY INVISIBLE (-700 3250);
FORCEPROP 1 LASTPIN (-750 3175) $PN 1
J 0
(-745 3137);
DISPLAY 0.787234 (-745 3137);
PAINT MONO (-745 3137);
FORCEPROP 1 LASTPIN (-750 2975) $PN 2
J 0
(-745 2985);
DISPLAY 0.787234 (-745 2985);
PAINT MONO (-745 2985);
FORCEPROP 2 LAST ROOM USB2 BOM1
J 0
(-700 3225);
DISPLAY 0.553191 (-700 3225);
PAINT RED (-700 3225);
FORCEPROP 1 LAST PACK_TYPE 0402LF
J 0
(-710 2900);
DISPLAY 0.468085 (-710 2900);
FORCEPROP 1 LAST MATERIAL CHIP
J 0
(-710 3000);
DISPLAY 0.468085 (-710 3000);
FORCEPROP 1 LAST WATTAGE 1/16W
J 0
(-710 3050);
DISPLAY 0.468085 (-710 3050);
FORCEPROP 1 LAST TOLERANCE 1%
J 0
(-705 3100);
DISPLAY 0.468085 (-705 3100);
FORCEPROP 1 LAST VALUE 100K
J 0
(-705 3150);
DISPLAY 0.468085 (-705 3150);
FORCEPROP 2 LAST CDS_LIB pure_quanta
J 0
(-750 3075);
DISPLAY INVISIBLE (-750 3075);
FORCEPROP 1 LAST PATH I182
J 0
(-700 3250);
DISPLAY 0.978723 (-700 3250);
PAINT WHITE (-700 3250);
DISPLAY INVISIBLE (-700 3250);
FORCEPROP 1 LAST PART_NUMBER CS41002FB09
J 0
(-710 2950);
DISPLAY 0.468085 (-710 2950);
DISPLAY INVISIBLE (-710 2950);
FORCEADD UNIVERSAL_GND..1
(-750 2800);
FORCEPROP 3 LASTPIN (-750 2850) SIG_NAME GND\g
J 0
(-740 2860);
DISPLAY 0.659574 (-740 2860);
PAINT MONO (-740 2860);
DISPLAY INVISIBLE (-740 2860);
FORCEPROP 2 LAST CDS_LIB pure_quanta_power
J 0
(-750 2800);
DISPLAY INVISIBLE (-750 2800);
FORCEPROP 1 LAST HDL_POWER GND
J 1
(-725 2725);
DISPLAY 0.872340 (-725 2725);
PAINT GREEN (-725 2725);
DISPLAY INVISIBLE (-725 2725);
FORCEPROP 1 LAST PATH I183
J 0
(-675 2800);
DISPLAY 0.872340 (-675 2800);
PAINT AQUA (-675 2800);
DISPLAY INVISIBLE (-675 2800);
FORCEADD OFFPAGE..1
(-875 3375);
PAINT AQUA (-875 3375);
FORCEPROP 2 LAST $XR0 235 
J 0
(-1187 3375);
DISPLAY 0.638298 (-1187 3375);
PAINT MONO (-1187 3375);
FORCEPROP 2 LAST CDS_LIB standard
J 0
(-875 3375);
DISPLAY INVISIBLE (-875 3375);
FORCEPROP 1 LAST OFFPAGE TRUE
J 0
(-550 3250);
DISPLAY 0.872340 (-550 3250);
PAINT AQUA (-550 3250);
DISPLAY INVISIBLE (-550 3250);
FORCEPROP 1 LAST COMMENT_BODY TRUE
J 0
(-750 3275);
DISPLAY 0.872340 (-750 3275);
PAINT GREEN (-750 3275);
DISPLAY INVISIBLE (-750 3275);
FORCEPROP 2 LAST PATH I184
J 0
(-825 3450);
DISPLAY 1.021277 (-825 3450);
DISPLAY INVISIBLE (-825 3450);
FORCEADD UNIVERSAL_POWER..1
R 2
(-4150 3400);
FORCEPROP 3 LASTPIN (-4150 3350) SIG_NAME P3V3_AUX\g
J 0
(-4140 3360);
DISPLAY 0.659574 (-4140 3360);
PAINT MONO (-4140 3360);
DISPLAY INVISIBLE (-4140 3360);
FORCEPROP 1 LAST HDL_POWER P3V3_AUX
J 1
(-4150 3450);
DISPLAY 0.723404 (-4150 3450);
PAINT GREEN (-4150 3450);
FORCEPROP 2 LAST CDS_LIB pure_quanta_power
J 0
(-4150 3400);
DISPLAY INVISIBLE (-4150 3400);
FORCEPROP 1 LAST PATH I185
J 2
(-4200 3425);
DISPLAY 0.872340 (-4200 3425);
PAINT AQUA (-4200 3425);
DISPLAY INVISIBLE (-4200 3425);
FORCEADD Q_RES..2
(-4150 2950);
FORCEPROP 1 LAST LOCATION R3663
J 0
(-4105 3075);
DISPLAY 0.978723 (-4105 3075);
FORCEPROP 0 LAST $SEC 1
J 0
(-4100 3125);
DISPLAY 0.680851 (-4100 3125);
PAINT MONO (-4100 3125);
DISPLAY INVISIBLE (-4100 3125);
FORCEPROP 0 LAST CDS_SEC 1
J 0
(-4100 3125);
DISPLAY 1.021277 (-4100 3125);
DISPLAY INVISIBLE (-4100 3125);
FORCEPROP 1 LASTPIN (-4150 3050) $PN 1
J 0
(-4145 3012);
DISPLAY 0.787234 (-4145 3012);
PAINT MONO (-4145 3012);
FORCEPROP 1 LASTPIN (-4150 2850) $PN 2
J 0
(-4145 2860);
DISPLAY 0.787234 (-4145 2860);
PAINT MONO (-4145 2860);
FORCEPROP 1 LAST PACK_TYPE 0402LF
J 0
(-4110 2775);
DISPLAY 0.723404 (-4110 2775);
PAINT SKYBLUE (-4110 2775);
FORCEPROP 1 LAST VALUE 10K
J 0
(-4105 3025);
DISPLAY 0.723404 (-4105 3025);
PAINT SKYBLUE (-4105 3025);
FORCEPROP 1 LAST TOLERANCE 1%
J 0
(-4105 2975);
DISPLAY 0.723404 (-4105 2975);
PAINT SKYBLUE (-4105 2975);
FORCEPROP 1 LAST WATTAGE 1/16W
J 0
(-4110 2925);
DISPLAY 0.723404 (-4110 2925);
PAINT SKYBLUE (-4110 2925);
FORCEPROP 1 LAST MATERIAL CHIP
J 0
(-4110 2875);
DISPLAY 0.723404 (-4110 2875);
PAINT SKYBLUE (-4110 2875);
FORCEPROP 2 LAST ROOM USB2 BOM1
J 0
(-4100 3125);
DISPLAY 0.680851 (-4100 3125);
PAINT RED (-4100 3125);
FORCEPROP 2 LAST CDS_LIB pure_quanta
J 0
(-4150 2950);
DISPLAY INVISIBLE (-4150 2950);
FORCEPROP 1 LAST PATH I186
J 0
(-4100 3125);
DISPLAY 0.978723 (-4100 3125);
PAINT WHITE (-4100 3125);
DISPLAY INVISIBLE (-4100 3125);
FORCEPROP 1 LAST PART_NUMBER CS31002FB08
J 0
(-4110 2825);
DISPLAY 0.723404 (-4110 2825);
PAINT WHITE (-4110 2825);
DISPLAY INVISIBLE (-4110 2825);
FORCEADD Q_RES..2
(-4150 2350);
FORCEPROP 1 LAST LOCATION R3664
J 0
(-4105 2475);
DISPLAY 0.978723 (-4105 2475);
FORCEPROP 0 LAST $SEC 1
J 0
(-4100 2525);
DISPLAY 0.680851 (-4100 2525);
PAINT MONO (-4100 2525);
DISPLAY INVISIBLE (-4100 2525);
FORCEPROP 0 LAST CDS_SEC 1
J 0
(-4100 2525);
DISPLAY 1.021277 (-4100 2525);
DISPLAY INVISIBLE (-4100 2525);
FORCEPROP 1 LASTPIN (-4150 2450) $PN 1
J 0
(-4145 2412);
DISPLAY 0.787234 (-4145 2412);
PAINT MONO (-4145 2412);
FORCEPROP 1 LASTPIN (-4150 2250) $PN 2
J 0
(-4145 2260);
DISPLAY 0.787234 (-4145 2260);
PAINT MONO (-4145 2260);
FORCEPROP 1 LAST PACK_TYPE 0402LF
J 0
(-4110 2175);
DISPLAY 0.723404 (-4110 2175);
PAINT SKYBLUE (-4110 2175);
FORCEPROP 1 LAST VALUE 10K
J 0
(-4105 2425);
DISPLAY 0.723404 (-4105 2425);
PAINT SKYBLUE (-4105 2425);
FORCEPROP 1 LAST TOLERANCE 1%
J 0
(-4105 2375);
DISPLAY 0.723404 (-4105 2375);
PAINT SKYBLUE (-4105 2375);
FORCEPROP 1 LAST MATERIAL EMPTY
J 0
(-4110 2275);
DISPLAY 0.723404 (-4110 2275);
PAINT RED (-4110 2275);
FORCEPROP 1 LAST WATTAGE 1/16W
J 0
(-4110 2325);
DISPLAY 0.723404 (-4110 2325);
PAINT SKYBLUE (-4110 2325);
FORCEPROP 2 LAST ROOM USB2 BOM1
J 0
(-4100 2525);
DISPLAY 0.680851 (-4100 2525);
PAINT RED (-4100 2525);
FORCEPROP 2 LAST CDS_LIB pure_quanta
J 0
(-4150 2350);
DISPLAY INVISIBLE (-4150 2350);
FORCEPROP 1 LAST PATH I187
J 0
(-4100 2525);
DISPLAY 0.978723 (-4100 2525);
PAINT WHITE (-4100 2525);
DISPLAY INVISIBLE (-4100 2525);
FORCEPROP 1 LAST PART_NUMBER CS31002FB08
J 0
(-4110 2225);
DISPLAY 0.723404 (-4110 2225);
PAINT WHITE (-4110 2225);
DISPLAY INVISIBLE (-4110 2225);
FORCEADD UNIVERSAL_GND..1
(-4150 1925);
FORCEPROP 3 LASTPIN (-4150 1975) SIG_NAME GND\g
J 0
(-4140 1985);
DISPLAY 0.659574 (-4140 1985);
PAINT MONO (-4140 1985);
DISPLAY INVISIBLE (-4140 1985);
FORCEPROP 2 LAST CDS_LIB pure_quanta_power
J 0
(-4150 1925);
DISPLAY INVISIBLE (-4150 1925);
FORCEPROP 1 LAST HDL_POWER GND
J 1
(-4125 1850);
DISPLAY 0.872340 (-4125 1850);
PAINT GREEN (-4125 1850);
DISPLAY INVISIBLE (-4125 1850);
FORCEPROP 1 LAST PATH I188
J 0
(-4075 1925);
DISPLAY 0.872340 (-4075 1925);
PAINT AQUA (-4075 1925);
DISPLAY INVISIBLE (-4075 1925);
FORCEADD OFFPAGE..5
R 2
(-3025 2625);
PAINT AQUA (-3025 2625);
FORCEPROP 2 LAST $XR0 235 
J 0
(-2836 2625);
DISPLAY 0.638298 (-2836 2625);
PAINT MONO (-2836 2625);
FORCEPROP 2 LAST CDS_LIB standard
J 2
(-3025 2625);
DISPLAY INVISIBLE (-3025 2625);
FORCEPROP 1 LAST OFFPAGE TRUE
J 2
(-3350 2500);
DISPLAY 0.872340 (-3350 2500);
PAINT AQUA (-3350 2500);
DISPLAY INVISIBLE (-3350 2500);
FORCEPROP 1 LAST COMMENT_BODY TRUE
J 2
(-3125 2550);
DISPLAY 1.170213 (-3125 2550);
PAINT GREEN (-3125 2550);
DISPLAY INVISIBLE (-3125 2550);
FORCEPROP 2 LAST PATH I189
J 2
(-3075 2700);
DISPLAY 1.021277 (-3075 2700);
DISPLAY INVISIBLE (-3075 2700);
FORCEADD OFFPAGE..5
R 2
(-825 2275);
FORCEPROP 2 LAST $XR0 235 
J 0
(-636 2275);
DISPLAY 0.638298 (-636 2275);
PAINT MONO (-636 2275);
FORCEPROP 2 LAST CDS_LIB standard
J 2
(-825 2275);
DISPLAY INVISIBLE (-825 2275);
FORCEPROP 1 LAST OFFPAGE TRUE
J 2
(-1150 2150);
DISPLAY 0.872340 (-1150 2150);
PAINT GREEN (-1150 2150);
DISPLAY INVISIBLE (-1150 2150);
FORCEPROP 1 LAST COMMENT_BODY TRUE
J 2
(-925 2200);
DISPLAY 0.872340 (-925 2200);
PAINT GREEN (-925 2200);
DISPLAY INVISIBLE (-925 2200);
FORCEPROP 2 LAST PATH I190
J 0
(-650 2350);
DISPLAY 1.021277 (-650 2350);
DISPLAY INVISIBLE (-650 2350);
FORCEADD OFFPAGE..5
R 2
(-825 2125);
FORCEPROP 2 LAST $XR0 235 
J 0
(-636 2125);
DISPLAY 0.638298 (-636 2125);
PAINT MONO (-636 2125);
FORCEPROP 2 LAST CDS_LIB standard
J 0
(-825 2125);
DISPLAY INVISIBLE (-825 2125);
FORCEPROP 1 LAST OFFPAGE TRUE
J 2
(-1150 2000);
DISPLAY 0.872340 (-1150 2000);
PAINT GREEN (-1150 2000);
DISPLAY INVISIBLE (-1150 2000);
FORCEPROP 1 LAST COMMENT_BODY TRUE
J 2
(-925 2050);
DISPLAY 0.872340 (-925 2050);
PAINT GREEN (-925 2050);
DISPLAY INVISIBLE (-925 2050);
FORCEPROP 2 LAST PATH I191
J 0
(-650 2200);
DISPLAY 1.021277 (-650 2200);
DISPLAY INVISIBLE (-650 2200);
FORCEADD OFFPAGE..5
R 2
(-825 2000);
FORCEPROP 2 LAST $XR0 235 
J 0
(-636 2000);
DISPLAY 0.638298 (-636 2000);
PAINT MONO (-636 2000);
FORCEPROP 2 LAST CDS_LIB standard
J 0
(-825 2000);
DISPLAY INVISIBLE (-825 2000);
FORCEPROP 1 LAST OFFPAGE TRUE
J 2
(-1150 1875);
DISPLAY 0.872340 (-1150 1875);
PAINT GREEN (-1150 1875);
DISPLAY INVISIBLE (-1150 1875);
FORCEPROP 1 LAST COMMENT_BODY TRUE
J 2
(-925 1925);
DISPLAY 0.872340 (-925 1925);
PAINT GREEN (-925 1925);
DISPLAY INVISIBLE (-925 1925);
FORCEPROP 2 LAST PATH I192
J 0
(-650 2075);
DISPLAY 1.021277 (-650 2075);
DISPLAY INVISIBLE (-650 2075);
FORCEADD OFFPAGE..5
R 2
(-825 1875);
FORCEPROP 2 LAST $XR0 235 
J 0
(-636 1875);
DISPLAY 0.638298 (-636 1875);
PAINT MONO (-636 1875);
FORCEPROP 2 LAST CDS_LIB standard
J 0
(-825 1875);
DISPLAY INVISIBLE (-825 1875);
FORCEPROP 1 LAST OFFPAGE TRUE
J 2
(-1150 1750);
DISPLAY 0.872340 (-1150 1750);
PAINT GREEN (-1150 1750);
DISPLAY INVISIBLE (-1150 1750);
FORCEPROP 1 LAST COMMENT_BODY TRUE
J 2
(-925 1800);
DISPLAY 0.872340 (-925 1800);
PAINT GREEN (-925 1800);
DISPLAY INVISIBLE (-925 1800);
FORCEPROP 2 LAST PATH I193
J 0
(-650 1950);
DISPLAY 1.021277 (-650 1950);
DISPLAY INVISIBLE (-650 1950);
FORCEADD Q_RES..1
(-1550 2275);
FORCEPROP 1 LAST LOCATION R3656
J 0
(-1800 2275);
DISPLAY 0.638298 (-1800 2275);
FORCEPROP 0 LAST $SEC 1
J 0
(-1700 2350);
DISPLAY 0.680851 (-1700 2350);
PAINT MONO (-1700 2350);
DISPLAY INVISIBLE (-1700 2350);
FORCEPROP 0 LAST CDS_SEC 1
J 0
(-1700 2350);
DISPLAY 1.021277 (-1700 2350);
DISPLAY INVISIBLE (-1700 2350);
FORCEPROP 1 LASTPIN (-1650 2275) $PN 1
J 0
(-1638 2287);
DISPLAY 0.787234 (-1638 2287);
PAINT MONO (-1638 2287);
FORCEPROP 1 LASTPIN (-1450 2275) $PN 2
J 0
(-1488 2287);
DISPLAY 0.787234 (-1488 2287);
PAINT MONO (-1488 2287);
FORCEPROP 2 LAST ROOM USB2 BOM1
J 0
(-1975 2350);
DISPLAY 0.680851 (-1975 2350);
PAINT RED (-1975 2350);
FORCEPROP 1 LAST MATERIAL EMPTY
J 0
(-1525 2225);
DISPLAY 0.638298 (-1525 2225);
PAINT RED (-1525 2225);
FORCEPROP 1 LAST VALUE 10K
J 2
(-1575 2225);
DISPLAY 0.638298 (-1575 2225);
FORCEPROP 2 LAST CDS_LIB pure_quanta
J 0
(-1550 2275);
DISPLAY INVISIBLE (-1550 2275);
FORCEPROP 1 LAST PACK_TYPE 0402LF
J 0
(-1450 2225);
DISPLAY 0.638298 (-1450 2225);
DISPLAY INVISIBLE (-1450 2225);
FORCEPROP 1 LAST TOLERANCE 1%
J 0
(-1550 2225);
DISPLAY 0.638298 (-1550 2225);
DISPLAY INVISIBLE (-1550 2225);
FORCEPROP 1 LAST WATTAGE 1/16W
J 2
(-1575 2175);
DISPLAY 0.638298 (-1575 2175);
DISPLAY INVISIBLE (-1575 2175);
FORCEPROP 1 LAST PATH I194
J 0
(-1600 2425);
DISPLAY 0.978723 (-1600 2425);
PAINT WHITE (-1600 2425);
DISPLAY INVISIBLE (-1600 2425);
FORCEPROP 1 LAST PART_NUMBER CS31002FB08
J 0
(-1725 2125);
DISPLAY 0.638298 (-1725 2125);
DISPLAY INVISIBLE (-1725 2125);
FORCEADD Q_RES..1
(-1550 2125);
FORCEPROP 1 LAST LOCATION R3657
J 0
(-1800 2125);
DISPLAY 0.638298 (-1800 2125);
FORCEPROP 0 LAST $SEC 1
J 0
(-1700 2200);
DISPLAY 0.680851 (-1700 2200);
PAINT MONO (-1700 2200);
DISPLAY INVISIBLE (-1700 2200);
FORCEPROP 0 LAST CDS_SEC 1
J 0
(-1700 2200);
DISPLAY 1.021277 (-1700 2200);
DISPLAY INVISIBLE (-1700 2200);
FORCEPROP 1 LASTPIN (-1650 2125) $PN 1
J 0
(-1638 2137);
DISPLAY 0.787234 (-1638 2137);
PAINT MONO (-1638 2137);
FORCEPROP 1 LASTPIN (-1450 2125) $PN 2
J 0
(-1488 2137);
DISPLAY 0.787234 (-1488 2137);
PAINT MONO (-1488 2137);
FORCEPROP 1 LAST MATERIAL EMPTY
J 0
(-1525 2075);
DISPLAY 0.638298 (-1525 2075);
PAINT RED (-1525 2075);
FORCEPROP 1 LAST VALUE 10K
J 2
(-1575 2075);
DISPLAY 0.638298 (-1575 2075);
FORCEPROP 2 LAST ROOM USB2 BOM1
J 0
(-1950 2175);
DISPLAY 0.680851 (-1950 2175);
PAINT RED (-1950 2175);
FORCEPROP 2 LAST CDS_LIB pure_quanta
J 0
(-1550 2125);
DISPLAY INVISIBLE (-1550 2125);
FORCEPROP 1 LAST WATTAGE 1/16W
J 2
(-1575 2025);
DISPLAY 0.638298 (-1575 2025);
DISPLAY INVISIBLE (-1575 2025);
FORCEPROP 1 LAST TOLERANCE 1%
J 0
(-1550 2075);
DISPLAY 0.638298 (-1550 2075);
DISPLAY INVISIBLE (-1550 2075);
FORCEPROP 1 LAST PACK_TYPE 0402LF
J 0
(-1450 2075);
DISPLAY 0.638298 (-1450 2075);
DISPLAY INVISIBLE (-1450 2075);
FORCEPROP 1 LAST PATH I195
J 0
(-1600 2275);
DISPLAY 0.978723 (-1600 2275);
PAINT WHITE (-1600 2275);
DISPLAY INVISIBLE (-1600 2275);
FORCEPROP 1 LAST PART_NUMBER CS31002FB08
J 0
(-1725 1975);
DISPLAY 0.638298 (-1725 1975);
DISPLAY INVISIBLE (-1725 1975);
FORCEADD Q_RES..1
(-1550 2000);
FORCEPROP 1 LAST LOCATION R3658
J 0
(-1825 2000);
DISPLAY 0.638298 (-1825 2000);
FORCEPROP 0 LAST $SEC 1
J 0
(-1700 2075);
DISPLAY 0.680851 (-1700 2075);
PAINT MONO (-1700 2075);
DISPLAY INVISIBLE (-1700 2075);
FORCEPROP 0 LAST CDS_SEC 1
J 0
(-1700 2075);
DISPLAY 1.021277 (-1700 2075);
DISPLAY INVISIBLE (-1700 2075);
FORCEPROP 1 LASTPIN (-1650 2000) $PN 1
J 0
(-1638 2012);
DISPLAY 0.787234 (-1638 2012);
PAINT MONO (-1638 2012);
FORCEPROP 1 LASTPIN (-1450 2000) $PN 2
J 0
(-1488 2012);
DISPLAY 0.787234 (-1488 2012);
PAINT MONO (-1488 2012);
FORCEPROP 1 LAST VALUE 10K
J 2
(-1575 1950);
DISPLAY 0.638298 (-1575 1950);
FORCEPROP 2 LAST ROOM USB2 BOM1
J 0
(-1950 2050);
DISPLAY 0.680851 (-1950 2050);
PAINT RED (-1950 2050);
FORCEPROP 1 LAST MATERIAL EMPTY
J 0
(-1525 1950);
DISPLAY 0.638298 (-1525 1950);
PAINT RED (-1525 1950);
FORCEPROP 2 LAST CDS_LIB pure_quanta
J 0
(-1550 2000);
DISPLAY INVISIBLE (-1550 2000);
FORCEPROP 1 LAST PACK_TYPE 0402LF
J 0
(-1450 1950);
DISPLAY 0.638298 (-1450 1950);
DISPLAY INVISIBLE (-1450 1950);
FORCEPROP 1 LAST TOLERANCE 1%
J 0
(-1550 1950);
DISPLAY 0.638298 (-1550 1950);
DISPLAY INVISIBLE (-1550 1950);
FORCEPROP 1 LAST WATTAGE 1/16W
J 2
(-1575 1900);
DISPLAY 0.638298 (-1575 1900);
DISPLAY INVISIBLE (-1575 1900);
FORCEPROP 1 LAST PATH I196
J 0
(-1600 2150);
DISPLAY 0.978723 (-1600 2150);
PAINT WHITE (-1600 2150);
DISPLAY INVISIBLE (-1600 2150);
FORCEPROP 1 LAST PART_NUMBER CS31002FB08
J 0
(-1725 1850);
DISPLAY 0.638298 (-1725 1850);
DISPLAY INVISIBLE (-1725 1850);
FORCEADD UNIVERSAL_POWER..1
R 2
(-2175 2525);
FORCEPROP 3 LASTPIN (-2175 2475) SIG_NAME P3V3_AUX\g
J 0
(-2165 2485);
DISPLAY 0.659574 (-2165 2485);
PAINT MONO (-2165 2485);
DISPLAY INVISIBLE (-2165 2485);
FORCEPROP 1 LAST HDL_POWER P3V3_AUX
J 1
(-2175 2575);
DISPLAY 0.723404 (-2175 2575);
PAINT GREEN (-2175 2575);
FORCEPROP 2 LAST CDS_LIB pure_quanta_power
J 0
(-2175 2525);
DISPLAY INVISIBLE (-2175 2525);
FORCEPROP 1 LAST PATH I197
J 2
(-2225 2550);
DISPLAY 0.872340 (-2225 2550);
PAINT AQUA (-2225 2550);
DISPLAY INVISIBLE (-2225 2550);
FORCEADD Q_RES..1
(-1550 1875);
FORCEPROP 1 LAST LOCATION R3659
J 0
(-1800 1875);
DISPLAY 0.638298 (-1800 1875);
FORCEPROP 0 LAST $SEC 1
J 0
(-1700 1925);
DISPLAY 0.680851 (-1700 1925);
PAINT MONO (-1700 1925);
DISPLAY INVISIBLE (-1700 1925);
FORCEPROP 0 LAST CDS_SEC 1
J 0
(-1700 1925);
DISPLAY 1.021277 (-1700 1925);
DISPLAY INVISIBLE (-1700 1925);
FORCEPROP 1 LASTPIN (-1650 1875) $PN 1
J 0
(-1638 1887);
DISPLAY 0.787234 (-1638 1887);
PAINT MONO (-1638 1887);
FORCEPROP 1 LASTPIN (-1450 1875) $PN 2
J 0
(-1488 1887);
DISPLAY 0.787234 (-1488 1887);
PAINT MONO (-1488 1887);
FORCEPROP 2 LAST ROOM USB2 BOM1
J 0
(-1950 1925);
DISPLAY 0.680851 (-1950 1925);
PAINT RED (-1950 1925);
FORCEPROP 1 LAST VALUE 10K
J 2
(-1575 1825);
DISPLAY 0.638298 (-1575 1825);
FORCEPROP 1 LAST WATTAGE 1/16W
J 2
(-1575 1775);
DISPLAY 0.638298 (-1575 1775);
FORCEPROP 1 LAST TOLERANCE 1%
J 0
(-1550 1825);
DISPLAY 0.638298 (-1550 1825);
FORCEPROP 1 LAST MATERIAL EMPTY
J 0
(-1550 1775);
DISPLAY 0.638298 (-1550 1775);
PAINT RED (-1550 1775);
FORCEPROP 1 LAST PACK_TYPE 0402LF
J 0
(-1450 1825);
DISPLAY 0.638298 (-1450 1825);
FORCEPROP 2 LAST CDS_LIB pure_quanta
J 0
(-1550 1875);
DISPLAY INVISIBLE (-1550 1875);
FORCEPROP 1 LAST PATH I198
J 0
(-1600 2025);
DISPLAY 0.978723 (-1600 2025);
PAINT WHITE (-1600 2025);
DISPLAY INVISIBLE (-1600 2025);
FORCEPROP 1 LAST PART_NUMBER CS31002FB08
J 0
(-1725 1725);
DISPLAY 0.638298 (-1725 1725);
DISPLAY INVISIBLE (-1725 1725);
FORCEADD Q_RES..1
(1375 4275);
FORCEPROP 1 LAST LOCATION R3666
J 0
(1125 4275);
DISPLAY 0.638298 (1125 4275);
FORCEPROP 0 LAST $SEC 1
J 0
(1550 4325);
DISPLAY 0.680851 (1550 4325);
PAINT MONO (1550 4325);
DISPLAY INVISIBLE (1550 4325);
FORCEPROP 0 LAST CDS_SEC 1
J 0
(1550 4325);
DISPLAY 1.021277 (1550 4325);
DISPLAY INVISIBLE (1550 4325);
FORCEPROP 1 LASTPIN (1275 4275) $PN 1
J 0
(1287 4287);
DISPLAY 0.787234 (1287 4287);
PAINT MONO (1287 4287);
FORCEPROP 1 LASTPIN (1475 4275) $PN 2
J 0
(1437 4287);
DISPLAY 0.787234 (1437 4287);
PAINT MONO (1437 4287);
FORCEPROP 1 LAST PACK_TYPE 0402LF
J 0
(1550 4275);
DISPLAY 0.723404 (1550 4275);
FORCEPROP 1 LAST MATERIAL CHIP
J 0
(1550 4225);
DISPLAY 0.723404 (1550 4225);
FORCEPROP 2 LAST ROOM USB2 BOM1
J 0
(1550 4325);
DISPLAY 0.680851 (1550 4325);
PAINT RED (1550 4325);
FORCEPROP 1 LAST VALUE 0
J 2
(1525 4275);
DISPLAY 0.723404 (1525 4275);
FORCEPROP 1 LAST WATTAGE 1/16W
J 2
(1450 4200);
DISPLAY 0.723404 (1450 4200);
PAINT SKYBLUE (1450 4200);
DISPLAY INVISIBLE (1450 4200);
FORCEPROP 1 LAST TOLERANCE 5%
J 0
(1175 4200);
DISPLAY 0.723404 (1175 4200);
PAINT SKYBLUE (1175 4200);
DISPLAY INVISIBLE (1175 4200);
FORCEPROP 2 LAST CDS_LIB pure_quanta
J 0
(1375 4275);
DISPLAY INVISIBLE (1375 4275);
FORCEPROP 1 LAST PATH I199
J 0
(1325 4425);
DISPLAY 0.978723 (1325 4425);
PAINT WHITE (1325 4425);
DISPLAY INVISIBLE (1325 4425);
FORCEPROP 1 LAST PART_NUMBER CS00002JB13
J 0
(1100 4150);
DISPLAY 0.723404 (1100 4150);
PAINT WHITE (1100 4150);
DISPLAY INVISIBLE (1100 4150);
FORCEADD Q_RES..1
R 1
(-1900 3100);
FORCEPROP 1 LAST LOCATION R3661
J 0
(-1825 3225);
DISPLAY 0.638298 (-1825 3225);
FORCEPROP 0 LAST $SEC 1
R 1
J 0
(-1825 3275);
DISPLAY 0.680851 (-1825 3275);
PAINT MONO (-1825 3275);
DISPLAY INVISIBLE (-1825 3275);
FORCEPROP 0 LAST CDS_SEC 1
R 1
J 0
(-1825 3275);
DISPLAY 1.021277 (-1825 3275);
DISPLAY INVISIBLE (-1825 3275);
FORCEPROP 1 LASTPIN (-1900 3000) $PN 1
R 1
J 0
(-1912 3012);
DISPLAY 0.787234 (-1912 3012);
PAINT MONO (-1912 3012);
FORCEPROP 1 LASTPIN (-1900 3200) $PN 2
R 1
J 0
(-1912 3162);
DISPLAY 0.787234 (-1912 3162);
PAINT MONO (-1912 3162);
FORCEPROP 1 LAST PACK_TYPE 0402LF
J 0
(-1825 2925);
DISPLAY 0.638298 (-1825 2925);
FORCEPROP 1 LAST WATTAGE 1/16W
J 2
(-1675 3075);
DISPLAY 0.638298 (-1675 3075);
FORCEPROP 1 LAST MATERIAL EMPTY
J 0
(-1825 3025);
DISPLAY 0.638298 (-1825 3025);
PAINT RED (-1825 3025);
FORCEPROP 1 LAST VALUE 47K
J 2
(-1725 3175);
DISPLAY 0.638298 (-1725 3175);
FORCEPROP 1 LAST TOLERANCE 0.1%
J 0
(-1825 3125);
DISPLAY 0.638298 (-1825 3125);
FORCEPROP 2 LAST CDS_LIB pure_quanta
R 1
J 0
(-1900 3100);
DISPLAY INVISIBLE (-1900 3100);
FORCEPROP 1 LAST PATH I201
R 1
J 0
(-2050 3050);
DISPLAY 0.978723 (-2050 3050);
PAINT WHITE (-2050 3050);
DISPLAY INVISIBLE (-2050 3050);
FORCEPROP 1 LAST PART_NUMBER CS34702BB05
J 0
(-1825 2975);
DISPLAY 0.638298 (-1825 2975);
DISPLAY INVISIBLE (-1825 2975);
FORCEADD Q_RES..2
(3625 3675);
FORCEPROP 1 LAST LOCATION R4420
J 0
(3675 3700);
DISPLAY 0.638298 (3675 3700);
FORCEPROP 0 LAST $SEC 1
J 0
(3675 3750);
DISPLAY 0.680851 (3675 3750);
PAINT MONO (3675 3750);
DISPLAY INVISIBLE (3675 3750);
FORCEPROP 0 LAST CDS_SEC 1
J 0
(3675 3750);
DISPLAY 1.021277 (3675 3750);
DISPLAY INVISIBLE (3675 3750);
FORCEPROP 1 LASTPIN (3625 3775) $PN 1
J 0
(3630 3737);
DISPLAY 0.787234 (3630 3737);
PAINT MONO (3630 3737);
FORCEPROP 1 LASTPIN (3625 3575) $PN 2
J 0
(3630 3585);
DISPLAY 0.787234 (3630 3585);
PAINT MONO (3630 3585);
FORCEPROP 1 LAST MATERIAL EMPTY
J 0
(3665 3600);
DISPLAY 0.510638 (3665 3600);
PAINT RED (3665 3600);
FORCEPROP 1 LAST VALUE 49.9
J 0
(3675 3650);
DISPLAY 0.510638 (3675 3650);
FORCEPROP 1 LAST PACK_TYPE 0402LF
J 0
(3675 3500);
DISPLAY 0.510638 (3675 3500);
DISPLAY INVISIBLE (3675 3500);
FORCEPROP 1 LAST TOLERANCE 1%
J 0
(3670 3700);
DISPLAY 0.510638 (3670 3700);
DISPLAY INVISIBLE (3670 3700);
FORCEPROP 1 LAST WATTAGE 1/16W
J 0
(3665 3650);
DISPLAY 0.510638 (3665 3650);
DISPLAY INVISIBLE (3665 3650);
FORCEPROP 2 LAST CDS_LIB pure_quanta
J 0
(3625 3675);
DISPLAY INVISIBLE (3625 3675);
FORCEPROP 1 LAST PATH I202
J 0
(3675 3850);
DISPLAY 0.978723 (3675 3850);
PAINT WHITE (3675 3850);
DISPLAY INVISIBLE (3675 3850);
FORCEPROP 1 LAST PART_NUMBER CS04992FB07
J 0
(3665 3550);
DISPLAY 0.510638 (3665 3550);
DISPLAY INVISIBLE (3665 3550);
FORCEADD Q_RES..2
(3450 3675);
FORCEPROP 1 LAST LOCATION R4419
J 0
(3500 3700);
DISPLAY 0.510638 (3500 3700);
FORCEPROP 0 LAST $SEC 1
J 0
(3500 3725);
DISPLAY 0.680851 (3500 3725);
PAINT MONO (3500 3725);
DISPLAY INVISIBLE (3500 3725);
FORCEPROP 0 LAST CDS_SEC 1
J 0
(3500 3725);
DISPLAY 1.021277 (3500 3725);
DISPLAY INVISIBLE (3500 3725);
FORCEPROP 1 LASTPIN (3450 3775) $PN 1
J 0
(3455 3737);
DISPLAY 0.787234 (3455 3737);
PAINT MONO (3455 3737);
FORCEPROP 1 LASTPIN (3450 3575) $PN 2
J 0
(3455 3585);
DISPLAY 0.787234 (3455 3585);
PAINT MONO (3455 3585);
FORCEPROP 1 LAST MATERIAL EMPTY
J 0
(3490 3600);
DISPLAY 0.510638 (3490 3600);
PAINT RED (3490 3600);
FORCEPROP 1 LAST VALUE 49.9
J 0
(3500 3650);
DISPLAY 0.510638 (3500 3650);
FORCEPROP 1 LAST WATTAGE 1/16W
J 0
(3490 3650);
DISPLAY 0.510638 (3490 3650);
DISPLAY INVISIBLE (3490 3650);
FORCEPROP 1 LAST TOLERANCE 1%
J 0
(3495 3700);
DISPLAY 0.510638 (3495 3700);
DISPLAY INVISIBLE (3495 3700);
FORCEPROP 1 LAST PACK_TYPE 0402LF
J 0
(3500 3500);
DISPLAY 0.510638 (3500 3500);
DISPLAY INVISIBLE (3500 3500);
FORCEPROP 2 LAST CDS_LIB pure_quanta
J 0
(3450 3675);
DISPLAY INVISIBLE (3450 3675);
FORCEPROP 1 LAST PATH I203
J 0
(3500 3850);
DISPLAY 0.978723 (3500 3850);
PAINT WHITE (3500 3850);
DISPLAY INVISIBLE (3500 3850);
FORCEPROP 1 LAST PART_NUMBER CS04992FB07
J 0
(3490 3550);
DISPLAY 0.510638 (3490 3550);
DISPLAY INVISIBLE (3490 3550);
FORCEADD UNIVERSAL_GND..1
(3625 3450);
FORCEPROP 3 LASTPIN (3625 3500) SIG_NAME GND\g
J 0
(3635 3510);
DISPLAY 0.659574 (3635 3510);
PAINT MONO (3635 3510);
DISPLAY INVISIBLE (3635 3510);
FORCEPROP 2 LAST CDS_LIB pure_quanta_power
J 0
(3625 3450);
DISPLAY INVISIBLE (3625 3450);
FORCEPROP 1 LAST HDL_POWER GND
J 1
(3650 3375);
DISPLAY 0.872340 (3650 3375);
PAINT GREEN (3650 3375);
DISPLAY INVISIBLE (3650 3375);
FORCEPROP 1 LAST PATH I204
J 0
(3700 3450);
DISPLAY 0.872340 (3700 3450);
PAINT AQUA (3700 3450);
DISPLAY INVISIBLE (3700 3450);
FORCEADD UNIVERSAL_GND..1
(3450 3450);
FORCEPROP 3 LASTPIN (3450 3500) SIG_NAME GND\g
J 0
(3460 3510);
DISPLAY 0.659574 (3460 3510);
PAINT MONO (3460 3510);
DISPLAY INVISIBLE (3460 3510);
FORCEPROP 2 LAST CDS_LIB pure_quanta_power
J 0
(3450 3450);
DISPLAY INVISIBLE (3450 3450);
FORCEPROP 1 LAST HDL_POWER GND
J 1
(3475 3375);
DISPLAY 0.872340 (3475 3375);
PAINT GREEN (3475 3375);
DISPLAY INVISIBLE (3475 3375);
FORCEPROP 1 LAST PATH I205
J 0
(3525 3450);
DISPLAY 0.872340 (3525 3450);
PAINT AQUA (3525 3450);
DISPLAY INVISIBLE (3525 3450);
FORCEADD Q_RES..2
(-2275 1025);
FORCEPROP 1 LAST LOCATION R4483
J 0
(-2230 1150);
DISPLAY 0.638298 (-2230 1150);
FORCEPROP 0 LAST $SEC 1
J 0
(-2225 1200);
DISPLAY 0.680851 (-2225 1200);
PAINT MONO (-2225 1200);
DISPLAY INVISIBLE (-2225 1200);
FORCEPROP 0 LAST CDS_SEC 1
J 0
(-2225 1200);
DISPLAY 1.021277 (-2225 1200);
DISPLAY INVISIBLE (-2225 1200);
FORCEPROP 1 LASTPIN (-2275 1125) $PN 1
J 0
(-2270 1087);
DISPLAY 0.787234 (-2270 1087);
PAINT MONO (-2270 1087);
FORCEPROP 1 LASTPIN (-2275 925) $PN 2
J 0
(-2270 935);
DISPLAY 0.787234 (-2270 935);
PAINT MONO (-2270 935);
FORCEPROP 1 LAST VALUE 49.9
J 0
(-2225 1000);
DISPLAY 0.510638 (-2225 1000);
FORCEPROP 1 LAST MATERIAL EMPTY
J 0
(-2235 950);
DISPLAY 0.510638 (-2235 950);
PAINT RED (-2235 950);
FORCEPROP 1 LAST PACK_TYPE 0402LF
J 0
(-2225 850);
DISPLAY 0.510638 (-2225 850);
DISPLAY INVISIBLE (-2225 850);
FORCEPROP 1 LAST TOLERANCE 1%
J 0
(-2230 1050);
DISPLAY 0.510638 (-2230 1050);
DISPLAY INVISIBLE (-2230 1050);
FORCEPROP 1 LAST WATTAGE 1/16W
J 0
(-2235 1000);
DISPLAY 0.510638 (-2235 1000);
DISPLAY INVISIBLE (-2235 1000);
FORCEPROP 2 LAST CDS_LIB pure_quanta
J 0
(-2275 1025);
DISPLAY INVISIBLE (-2275 1025);
FORCEPROP 1 LAST PATH I206
J 0
(-2225 1200);
DISPLAY 0.978723 (-2225 1200);
PAINT WHITE (-2225 1200);
DISPLAY INVISIBLE (-2225 1200);
FORCEPROP 1 LAST PART_NUMBER CS04992FB07
J 0
(-2235 900);
DISPLAY 0.510638 (-2235 900);
DISPLAY INVISIBLE (-2235 900);
FORCEADD UNIVERSAL_GND..1
(-2275 800);
FORCEPROP 3 LASTPIN (-2275 850) SIG_NAME GND\g
J 0
(-2265 860);
DISPLAY 0.659574 (-2265 860);
PAINT MONO (-2265 860);
DISPLAY INVISIBLE (-2265 860);
FORCEPROP 2 LAST CDS_LIB pure_quanta_power
J 0
(-2275 800);
DISPLAY INVISIBLE (-2275 800);
FORCEPROP 1 LAST HDL_POWER GND
J 1
(-2250 725);
DISPLAY 0.872340 (-2250 725);
PAINT GREEN (-2250 725);
DISPLAY INVISIBLE (-2250 725);
FORCEPROP 1 LAST PATH I207
J 0
(-2200 800);
DISPLAY 0.872340 (-2200 800);
PAINT AQUA (-2200 800);
DISPLAY INVISIBLE (-2200 800);
FORCEADD Q_RES..2
(-2450 1025);
FORCEPROP 1 LAST LOCATION R4482
J 0
(-2405 1150);
DISPLAY 0.638298 (-2405 1150);
FORCEPROP 0 LAST $SEC 1
J 0
(-2400 1200);
DISPLAY 0.680851 (-2400 1200);
PAINT MONO (-2400 1200);
DISPLAY INVISIBLE (-2400 1200);
FORCEPROP 0 LAST CDS_SEC 1
J 0
(-2400 1200);
DISPLAY 1.021277 (-2400 1200);
DISPLAY INVISIBLE (-2400 1200);
FORCEPROP 1 LASTPIN (-2450 1125) $PN 1
J 0
(-2445 1087);
DISPLAY 0.787234 (-2445 1087);
PAINT MONO (-2445 1087);
FORCEPROP 1 LASTPIN (-2450 925) $PN 2
J 0
(-2445 935);
DISPLAY 0.787234 (-2445 935);
PAINT MONO (-2445 935);
FORCEPROP 1 LAST VALUE 49.9
J 0
(-2400 1000);
DISPLAY 0.510638 (-2400 1000);
FORCEPROP 1 LAST MATERIAL EMPTY
J 0
(-2410 950);
DISPLAY 0.510638 (-2410 950);
PAINT RED (-2410 950);
FORCEPROP 1 LAST WATTAGE 1/16W
J 0
(-2410 1000);
DISPLAY 0.510638 (-2410 1000);
DISPLAY INVISIBLE (-2410 1000);
FORCEPROP 1 LAST TOLERANCE 1%
J 0
(-2405 1050);
DISPLAY 0.510638 (-2405 1050);
DISPLAY INVISIBLE (-2405 1050);
FORCEPROP 1 LAST PACK_TYPE 0402LF
J 0
(-2400 850);
DISPLAY 0.510638 (-2400 850);
DISPLAY INVISIBLE (-2400 850);
FORCEPROP 2 LAST CDS_LIB pure_quanta
J 0
(-2450 1025);
DISPLAY INVISIBLE (-2450 1025);
FORCEPROP 1 LAST PATH I208
J 0
(-2400 1200);
DISPLAY 0.978723 (-2400 1200);
PAINT WHITE (-2400 1200);
DISPLAY INVISIBLE (-2400 1200);
FORCEPROP 1 LAST PART_NUMBER CS04992FB07
J 0
(-2410 900);
DISPLAY 0.510638 (-2410 900);
DISPLAY INVISIBLE (-2410 900);
FORCEADD UNIVERSAL_GND..1
(-2450 800);
FORCEPROP 3 LASTPIN (-2450 850) SIG_NAME GND\g
J 0
(-2440 860);
DISPLAY 0.659574 (-2440 860);
PAINT MONO (-2440 860);
DISPLAY INVISIBLE (-2440 860);
FORCEPROP 2 LAST CDS_LIB pure_quanta_power
J 0
(-2450 800);
DISPLAY INVISIBLE (-2450 800);
FORCEPROP 1 LAST HDL_POWER GND
J 1
(-2425 725);
DISPLAY 0.872340 (-2425 725);
PAINT GREEN (-2425 725);
DISPLAY INVISIBLE (-2425 725);
FORCEPROP 1 LAST PATH I209
J 0
(-2375 800);
DISPLAY 0.872340 (-2375 800);
PAINT AQUA (-2375 800);
DISPLAY INVISIBLE (-2375 800);
FORCEADD Q_XTAL_4P_13BI_24GND..1
(4025 4550);
FORCEPROP 1 LAST LOCATION Y8004
J 0
(3892 4916);
DISPLAY 0.723404 (3892 4916);
PAINT GREEN (3892 4916);
FORCEPROP 2 LAST SEC 1
J 0
(3900 5050);
DISPLAY 0.680851 (3900 5050);
PAINT MONO (3900 5050);
DISPLAY INVISIBLE (3900 5050);
FORCEPROP 2 LASTPIN (3750 4425) $PN 2
J 2
(3740 4435);
DISPLAY 0.680851 (3740 4435);
PAINT MONO (3740 4435);
FORCEPROP 2 LASTPIN (4300 4425) $PN 4
J 0
(4310 4435);
DISPLAY 0.680851 (4310 4435);
PAINT MONO (4310 4435);
FORCEPROP 2 LASTPIN (3750 4625) $PN 1
J 2
(3740 4635);
DISPLAY 0.680851 (3740 4635);
PAINT MONO (3740 4635);
FORCEPROP 2 LASTPIN (4300 4625) $PN 3
J 0
(4310 4635);
DISPLAY 0.680851 (4310 4635);
PAINT MONO (4310 4635);
FORCEPROP 1 LAST MATERIAL MISC
J 0
(3892 4729);
DISPLAY 0.723404 (3892 4729);
PAINT GREEN (3892 4729);
FORCEPROP 2 LAST ROOM USB2 BOM1
J 0
(3925 5050);
DISPLAY 0.680851 (3925 5050);
PAINT RED (3925 5050);
FORCEPROP 2 LAST VALUE 12MHZ
J 0
(3900 4950);
DISPLAY 1.063830 (3900 4950);
FORCEPROP 2 LAST PART_TYPE SMLF
J 0
(3925 5000);
DISPLAY 0.872340 (3925 5000);
FORCEPROP 2 LAST SEC_TYPE 
J 0
(3900 5050);
DISPLAY 0.680851 (3900 5050);
DISPLAY INVISIBLE (3900 5050);
FORCEPROP 2 LAST CDS_LIB pure_quanta
J 0
(4025 4550);
DISPLAY INVISIBLE (4025 4550);
FORCEPROP 1 LAST PIN_NAMES_ROTATE True
J 0
(4025 4550);
DISPLAY 0.489362 (4025 4550);
PAINT GREEN (4025 4550);
DISPLAY INVISIBLE (4025 4550);
FORCEPROP 1 LAST CDS_LMAN_SYM_OUTLINE -125,175,125,-175
J 0
(4025 4550);
DISPLAY 0.468085 (4025 4550);
PAINT GREEN (4025 4550);
DISPLAY INVISIBLE (4025 4550);
FORCEPROP 1 LAST PATH I210
J 0
(4150 4375);
DISPLAY 0.723404 (4150 4375);
PAINT GREEN (4150 4375);
DISPLAY INVISIBLE (4150 4375);
FORCEPROP 1 LAST PART_NUMBER BG6120000B0
J 0
(3892 4825);
DISPLAY 0.723404 (3892 4825);
PAINT GREEN (3892 4825);
DISPLAY INVISIBLE (3892 4825);
FORCEADD Q_CAP..1
(4475 4375);
FORCEPROP 1 LAST LOCATION C2030
J 0
(4525 4475);
DISPLAY 0.638298 (4525 4475);
FORCEPROP 0 LAST $SEC 1
J 0
(4525 4525);
DISPLAY 0.680851 (4525 4525);
PAINT MONO (4525 4525);
DISPLAY INVISIBLE (4525 4525);
FORCEPROP 0 LAST CDS_SEC 1
J 0
(4525 4525);
DISPLAY 0.680851 (4525 4525);
DISPLAY INVISIBLE (4525 4525);
FORCEPROP 1 LASTPIN (4475 4475) $PN 1
J 0
(4485 4455);
DISPLAY 0.787234 (4485 4455);
PAINT MONO (4485 4455);
FORCEPROP 1 LASTPIN (4475 4275) $PN 2
J 0
(4485 4255);
DISPLAY 0.787234 (4485 4255);
PAINT MONO (4485 4255);
FORCEPROP 1 LAST VOLTAGE 50V
J 0
(4525 4375);
DISPLAY 0.638298 (4525 4375);
FORCEPROP 1 LAST TOLERANCE 5%
J 0
(4525 4325);
DISPLAY 0.638298 (4525 4325);
FORCEPROP 1 LAST PACK_TYPE 0402
J 0
(4525 4175);
DISPLAY 0.638298 (4525 4175);
FORCEPROP 1 LAST MATERIAL C0G
J 0
(4525 4275);
DISPLAY 0.638298 (4525 4275);
FORCEPROP 1 LAST VALUE 15PF
J 0
(4525 4425);
DISPLAY 0.638298 (4525 4425);
FORCEPROP 2 LAST ROOM USB2 BOM1
J 0
(4525 4525);
DISPLAY 0.553191 (4525 4525);
PAINT RED (4525 4525);
FORCEPROP 2 LAST CDS_LIB pure_quanta
J 0
(4475 4375);
DISPLAY INVISIBLE (4475 4375);
FORCEPROP 1 LAST PATH I211
J 0
(4525 4525);
DISPLAY 0.978723 (4525 4525);
PAINT WHITE (4525 4525);
DISPLAY INVISIBLE (4525 4525);
FORCEPROP 1 LAST PART_NUMBER CH01506JB06
J 0
(4525 4225);
DISPLAY 0.510638 (4525 4225);
DISPLAY INVISIBLE (4525 4225);
FORCEADD Q_CAP..1
(3475 4375);
FORCEPROP 1 LAST LOCATION C2029
J 0
(3525 4475);
DISPLAY 0.638298 (3525 4475);
FORCEPROP 0 LAST $SEC 1
J 0
(3525 4525);
DISPLAY 0.680851 (3525 4525);
PAINT MONO (3525 4525);
DISPLAY INVISIBLE (3525 4525);
FORCEPROP 0 LAST CDS_SEC 1
J 0
(3525 4525);
DISPLAY 0.680851 (3525 4525);
DISPLAY INVISIBLE (3525 4525);
FORCEPROP 1 LASTPIN (3475 4475) $PN 1
J 0
(3485 4455);
DISPLAY 0.787234 (3485 4455);
PAINT MONO (3485 4455);
FORCEPROP 1 LASTPIN (3475 4275) $PN 2
J 0
(3485 4255);
DISPLAY 0.787234 (3485 4255);
PAINT MONO (3485 4255);
FORCEPROP 2 LAST ROOM USB2 BOM1
J 0
(3525 4525);
DISPLAY 0.553191 (3525 4525);
PAINT RED (3525 4525);
FORCEPROP 1 LAST MATERIAL C0G
J 0
(3525 4275);
DISPLAY 0.638298 (3525 4275);
FORCEPROP 1 LAST PACK_TYPE 0402
J 0
(3525 4175);
DISPLAY 0.638298 (3525 4175);
FORCEPROP 1 LAST VALUE 15PF
J 0
(3525 4425);
DISPLAY 0.638298 (3525 4425);
FORCEPROP 1 LAST VOLTAGE 50V
J 0
(3525 4375);
DISPLAY 0.638298 (3525 4375);
FORCEPROP 1 LAST TOLERANCE 5%
J 0
(3525 4325);
DISPLAY 0.638298 (3525 4325);
FORCEPROP 2 LAST CDS_LIB pure_quanta
J 0
(3475 4375);
DISPLAY INVISIBLE (3475 4375);
FORCEPROP 1 LAST PATH I212
J 0
(3525 4525);
DISPLAY 0.978723 (3525 4525);
PAINT WHITE (3525 4525);
DISPLAY INVISIBLE (3525 4525);
FORCEPROP 1 LAST PART_NUMBER CH01506JB06
J 0
(3525 4225);
DISPLAY 0.638298 (3525 4225);
DISPLAY INVISIBLE (3525 4225);
FORCEADD OFFPAGE..3
R 2
(-3550 175);
PAINT AQUA (-3550 175);
FORCEPROP 2 LAST $XR0 235 
J 0
(-3860 175);
DISPLAY 0.638298 (-3860 175);
PAINT MONO (-3860 175);
FORCEPROP 2 LAST CDS_LIB standard
J 2
(-3550 175);
DISPLAY INVISIBLE (-3550 175);
FORCEPROP 1 LAST OFFPAGE TRUE
J 2
(-3875 50);
DISPLAY 0.872340 (-3875 50);
PAINT AQUA (-3875 50);
DISPLAY INVISIBLE (-3875 50);
FORCEPROP 1 LAST COMMENT_BODY TRUE
J 2
(-3500 75);
DISPLAY 0.872340 (-3500 75);
PAINT GREEN (-3500 75);
DISPLAY INVISIBLE (-3500 75);
FORCEPROP 2 LAST PATH I76
J 0
(-3825 225);
DISPLAY 1.021277 (-3825 225);
DISPLAY INVISIBLE (-3825 225);
FORCEADD OFFPAGE..3
R 2
(-3550 225);
PAINT AQUA (-3550 225);
FORCEPROP 2 LAST $XR0 235 
J 0
(-3860 225);
DISPLAY 0.638298 (-3860 225);
PAINT MONO (-3860 225);
FORCEPROP 2 LAST CDS_LIB standard
J 2
(-3550 225);
DISPLAY INVISIBLE (-3550 225);
FORCEPROP 1 LAST OFFPAGE TRUE
J 2
(-3875 100);
DISPLAY 0.872340 (-3875 100);
PAINT AQUA (-3875 100);
DISPLAY INVISIBLE (-3875 100);
FORCEPROP 1 LAST COMMENT_BODY TRUE
J 2
(-3500 125);
DISPLAY 0.872340 (-3500 125);
PAINT GREEN (-3500 125);
DISPLAY INVISIBLE (-3500 125);
FORCEPROP 2 LAST PATH I77
J 0
(-3825 275);
DISPLAY 1.021277 (-3825 275);
DISPLAY INVISIBLE (-3825 275);
FORCEADD Q_RES..1
(-2175 175);
FORCEPROP 1 LAST LOCATION R2787
J 0
(-2400 175);
DISPLAY 0.723404 (-2400 175);
FORCEPROP 2 LAST $SEC 1
J 0
(-2225 375);
DISPLAY 0.680851 (-2225 375);
PAINT MONO (-2225 375);
DISPLAY INVISIBLE (-2225 375);
FORCEPROP 2 LAST CDS_SEC 1
J 0
(-2225 375);
DISPLAY 1.021277 (-2225 375);
DISPLAY INVISIBLE (-2225 375);
FORCEPROP 1 LASTPIN (-2275 175) $PN 1
J 0
(-2263 187);
DISPLAY 0.787234 (-2263 187);
PAINT MONO (-2263 187);
FORCEPROP 1 LASTPIN (-2075 175) $PN 2
J 0
(-2113 187);
DISPLAY 0.787234 (-2113 187);
PAINT MONO (-2113 187);
FORCEPROP 1 LAST VALUE 0
J 2
(-2025 175);
DISPLAY 0.723404 (-2025 175);
FORCEPROP 1 LAST MATERIAL CHIP
J 0
(-2850 175);
DISPLAY 0.723404 (-2850 175);
FORCEPROP 1 LAST PACK_TYPE 0402LF
J 0
(-2675 175);
DISPLAY 0.723404 (-2675 175);
FORCEPROP 2 LAST ROOM USB2 BOM1
J 0
(-2725 125);
DISPLAY 0.680851 (-2725 125);
PAINT RED (-2725 125);
FORCEPROP 2 LAST CDS_LIB pure_quanta
J 0
(-2175 175);
DISPLAY INVISIBLE (-2175 175);
FORCEPROP 1 LAST WATTAGE 1/16W
J 2
(-2100 100);
DISPLAY 0.723404 (-2100 100);
PAINT SKYBLUE (-2100 100);
DISPLAY INVISIBLE (-2100 100);
FORCEPROP 1 LAST TOLERANCE 5%
J 0
(-2375 100);
DISPLAY 0.723404 (-2375 100);
PAINT SKYBLUE (-2375 100);
DISPLAY INVISIBLE (-2375 100);
FORCEPROP 1 LAST PATH I78
J 0
(-2225 325);
DISPLAY 0.978723 (-2225 325);
PAINT WHITE (-2225 325);
DISPLAY INVISIBLE (-2225 325);
FORCEPROP 1 LAST PART_NUMBER CS00002JB13
J 0
(-2450 50);
DISPLAY 0.723404 (-2450 50);
PAINT WHITE (-2450 50);
DISPLAY INVISIBLE (-2450 50);
FORCEADD Q_RES..1
(-2175 225);
FORCEPROP 1 LAST LOCATION R2786
J 0
(-2400 225);
DISPLAY 0.723404 (-2400 225);
FORCEPROP 2 LAST $SEC 1
J 0
(-2225 425);
DISPLAY 0.680851 (-2225 425);
PAINT MONO (-2225 425);
DISPLAY INVISIBLE (-2225 425);
FORCEPROP 2 LAST CDS_SEC 1
J 0
(-2225 425);
DISPLAY 1.021277 (-2225 425);
DISPLAY INVISIBLE (-2225 425);
FORCEPROP 1 LASTPIN (-2275 225) $PN 1
J 0
(-2263 237);
DISPLAY 0.787234 (-2263 237);
PAINT MONO (-2263 237);
FORCEPROP 1 LASTPIN (-2075 225) $PN 2
J 0
(-2113 237);
DISPLAY 0.787234 (-2113 237);
PAINT MONO (-2113 237);
FORCEPROP 2 LAST ROOM USB2 BOM1
J 0
(-2725 275);
DISPLAY 0.680851 (-2725 275);
PAINT RED (-2725 275);
FORCEPROP 1 LAST VALUE 0
J 2
(-2025 225);
DISPLAY 0.723404 (-2025 225);
FORCEPROP 1 LAST MATERIAL CHIP
J 0
(-2850 225);
DISPLAY 0.723404 (-2850 225);
FORCEPROP 1 LAST PACK_TYPE 0402LF
J 0
(-2675 225);
DISPLAY 0.723404 (-2675 225);
FORCEPROP 2 LAST CDS_LIB pure_quanta
J 0
(-2175 225);
DISPLAY INVISIBLE (-2175 225);
FORCEPROP 1 LAST WATTAGE 1/16W
J 2
(-2100 150);
DISPLAY 0.723404 (-2100 150);
PAINT SKYBLUE (-2100 150);
DISPLAY INVISIBLE (-2100 150);
FORCEPROP 1 LAST TOLERANCE 5%
J 0
(-2375 150);
DISPLAY 0.723404 (-2375 150);
PAINT SKYBLUE (-2375 150);
DISPLAY INVISIBLE (-2375 150);
FORCEPROP 1 LAST PATH I79
J 0
(-2225 375);
DISPLAY 0.978723 (-2225 375);
PAINT WHITE (-2225 375);
DISPLAY INVISIBLE (-2225 375);
FORCEPROP 1 LAST PART_NUMBER CS00002JB13
J 0
(-2450 100);
DISPLAY 0.723404 (-2450 100);
PAINT WHITE (-2450 100);
DISPLAY INVISIBLE (-2450 100);
FORCEADD UNIVERSAL_GND..1
(-1150 -450);
FORCEPROP 3 LASTPIN (-1150 -400) SIG_NAME GND\g
J 0
(-1140 -390);
DISPLAY 0.659574 (-1140 -390);
PAINT MONO (-1140 -390);
DISPLAY INVISIBLE (-1140 -390);
FORCEPROP 2 LAST CDS_LIB pure_quanta_power
J 0
(-1150 -450);
DISPLAY INVISIBLE (-1150 -450);
FORCEPROP 1 LAST HDL_POWER GND
J 1
(-1125 -525);
DISPLAY 0.872340 (-1125 -525);
PAINT GREEN (-1125 -525);
DISPLAY INVISIBLE (-1125 -525);
FORCEPROP 1 LAST PATH I80
J 0
(-1075 -450);
DISPLAY 0.872340 (-1075 -450);
PAINT AQUA (-1075 -450);
DISPLAY INVISIBLE (-1075 -450);
FORCEADD Q_CAP..1
(-1150 -225);
FORCEPROP 1 LAST LOCATION C5232
J 0
(-1100 -125);
DISPLAY 0.723404 (-1100 -125);
PAINT AQUA (-1100 -125);
FORCEPROP 2 LAST $SEC 1
J 0
(-1100 -25);
DISPLAY 0.680851 (-1100 -25);
PAINT MONO (-1100 -25);
DISPLAY INVISIBLE (-1100 -25);
FORCEPROP 0 LAST CDS_SEC 1
J 0
(-1100 -75);
DISPLAY INVISIBLE (-1100 -75);
FORCEPROP 1 LASTPIN (-1150 -125) $PN 1
J 0
(-1140 -145);
DISPLAY 0.723404 (-1140 -145);
PAINT MONO (-1140 -145);
FORCEPROP 1 LASTPIN (-1150 -325) $PN 2
J 0
(-1140 -345);
DISPLAY 0.723404 (-1140 -345);
PAINT MONO (-1140 -345);
FORCEPROP 2 LAST ROOM USB2 BOM2
J 0
(-1100 -75);
DISPLAY 0.553191 (-1100 -75);
PAINT RED (-1100 -75);
FORCEPROP 1 LAST PACK_TYPE C0402
J 0
(-1100 -425);
DISPLAY 0.723404 (-1100 -425);
PAINT SKYBLUE (-1100 -425);
FORCEPROP 1 LAST VALUE 0.1UF
J 0
(-1100 -175);
DISPLAY 0.723404 (-1100 -175);
PAINT SKYBLUE (-1100 -175);
FORCEPROP 1 LAST VOLTAGE 25V
J 0
(-1100 -225);
DISPLAY 0.723404 (-1100 -225);
PAINT SKYBLUE (-1100 -225);
FORCEPROP 1 LAST TOLERANCE 10%
J 0
(-1100 -275);
DISPLAY 0.723404 (-1100 -275);
PAINT SKYBLUE (-1100 -275);
FORCEPROP 1 LAST MATERIAL EMPTY
J 0
(-1100 -325);
DISPLAY 0.723404 (-1100 -325);
PAINT SKYBLUE (-1100 -325);
FORCEPROP 2 LAST CDS_LIB pure_quanta
J 0
(-1150 -225);
DISPLAY INVISIBLE (-1150 -225);
FORCEPROP 1 LAST PATH I81
J 0
(-1100 -75);
DISPLAY 0.978723 (-1100 -75);
PAINT WHITE (-1100 -75);
DISPLAY INVISIBLE (-1100 -75);
FORCEPROP 1 LAST PART_NUMBER CH4104KEB00
J 0
(-1100 -375);
DISPLAY 0.723404 (-1100 -375);
PAINT WHITE (-1100 -375);
DISPLAY INVISIBLE (-1100 -375);
FORCEADD UNIVERSAL_GND..1
(-675 -450);
FORCEPROP 3 LASTPIN (-675 -400) SIG_NAME GND\g
J 0
(-665 -390);
DISPLAY 0.659574 (-665 -390);
PAINT MONO (-665 -390);
DISPLAY INVISIBLE (-665 -390);
FORCEPROP 2 LAST CDS_LIB pure_quanta_power
J 0
(-675 -450);
DISPLAY INVISIBLE (-675 -450);
FORCEPROP 1 LAST HDL_POWER GND
J 1
(-650 -525);
DISPLAY 0.872340 (-650 -525);
PAINT GREEN (-650 -525);
DISPLAY INVISIBLE (-650 -525);
FORCEPROP 1 LAST PATH I82
J 0
(-600 -450);
DISPLAY 0.872340 (-600 -450);
PAINT AQUA (-600 -450);
DISPLAY INVISIBLE (-600 -450);
FORCEADD Q_RES..2
(-675 -250);
FORCEPROP 1 LAST LOCATION R5238
J 0
(-630 -125);
DISPLAY 0.723404 (-630 -125);
PAINT AQUA (-630 -125);
FORCEPROP 0 LAST $SEC 1
J 0
(-625 -75);
DISPLAY INVISIBLE (-625 -75);
FORCEPROP 0 LAST CDS_SEC 1
J 0
(-625 -75);
DISPLAY INVISIBLE (-625 -75);
FORCEPROP 1 LASTPIN (-675 -150) $PN 1
J 0
(-670 -188);
DISPLAY 0.787234 (-670 -188);
PAINT MONO (-670 -188);
DISPLAY INVISIBLE (-670 -188);
FORCEPROP 1 LASTPIN (-675 -350) $PN 2
J 0
(-670 -340);
DISPLAY 0.787234 (-670 -340);
PAINT MONO (-670 -340);
DISPLAY INVISIBLE (-670 -340);
FORCEPROP 2 LAST ROOM USB2 BOM2
J 0
(-625 -75);
DISPLAY 0.553191 (-625 -75);
PAINT RED (-625 -75);
FORCEPROP 1 LAST WATTAGE 1/16W
J 0
(-635 -275);
DISPLAY 0.723404 (-635 -275);
PAINT SKYBLUE (-635 -275);
FORCEPROP 1 LAST VALUE 3.9K
J 0
(-630 -175);
DISPLAY 0.723404 (-630 -175);
PAINT SKYBLUE (-630 -175);
FORCEPROP 1 LAST MATERIAL EMPTY
J 0
(-635 -325);
DISPLAY 0.723404 (-635 -325);
PAINT SKYBLUE (-635 -325);
FORCEPROP 1 LAST TOLERANCE 5%
J 0
(-630 -225);
DISPLAY 0.723404 (-630 -225);
PAINT SKYBLUE (-630 -225);
FORCEPROP 1 LAST PACK_TYPE 0402LF
J 0
(-635 -425);
DISPLAY 0.723404 (-635 -425);
PAINT SKYBLUE (-635 -425);
FORCEPROP 2 LAST CDS_LIB pure_quanta
J 0
(-675 -250);
DISPLAY INVISIBLE (-675 -250);
FORCEPROP 1 LAST PATH I83
J 0
(-625 -75);
DISPLAY 0.978723 (-625 -75);
PAINT WHITE (-625 -75);
DISPLAY INVISIBLE (-625 -75);
FORCEPROP 1 LAST PART_NUMBER CS23902JB04
J 0
(-635 -375);
DISPLAY 0.723404 (-635 -375);
PAINT WHITE (-635 -375);
DISPLAY INVISIBLE (-635 -375);
FORCEADD TUSB211IRWBR..1
(-125 100);
FORCEPROP 1 LAST LOCATION U5201
J 0
(-352 424);
DISPLAY 0.723404 (-352 424);
PAINT AQUA (-352 424);
FORCEPROP 0 LAST $SEC 1
J 0
(-350 575);
DISPLAY INVISIBLE (-350 575);
FORCEPROP 0 LAST CDS_SEC 1
J 0
(-350 575);
DISPLAY INVISIBLE (-350 575);
FORCEPROP 0 LASTPIN (-500 75) $PN 4
J 2
(-510 85);
DISPLAY 0.808511 (-510 85);
FORCEPROP 0 LASTPIN (-500 175) $PN 1
J 2
(-510 185);
DISPLAY 0.808511 (-510 185);
FORCEPROP 0 LASTPIN (-500 225) $PN 2
J 2
(-510 235);
DISPLAY 0.808511 (-510 235);
FORCEPROP 0 LASTPIN (250 175) $PN 8
J 0
(260 185);
DISPLAY 0.808511 (260 185);
FORCEPROP 0 LASTPIN (250 225) $PN 7
J 0
(260 235);
DISPLAY 0.808511 (260 235);
FORCEPROP 0 LASTPIN (250 -25) $PN 9
J 0
(260 -15);
DISPLAY 0.808511 (260 -15);
FORCEPROP 0 LASTPIN (-500 -25) $PN 6
J 2
(-510 -15);
DISPLAY 0.808511 (-510 -15);
FORCEPROP 0 LASTPIN (250 25) $PN 10
J 0
(260 35);
DISPLAY 0.808511 (260 35);
FORCEPROP 0 LASTPIN (-500 25) $PN 5
J 2
(-510 35);
DISPLAY 0.808511 (-510 35);
FORCEPROP 0 LASTPIN (-500 125) $PN 3
J 2
(-510 135);
DISPLAY 0.808511 (-510 135);
FORCEPROP 0 LASTPIN (250 125) $PN 12
J 0
(260 135);
DISPLAY 0.808511 (260 135);
FORCEPROP 0 LASTPIN (250 75) $PN 11
J 0
(260 85);
DISPLAY 0.808511 (260 85);
FORCEPROP 1 LAST MATERIAL EMPTY
J 0
(-352 279);
DISPLAY 0.723404 (-352 279);
PAINT SKYBLUE (-352 279);
FORCEPROP 2 LAST VALUE TUSB211IRWBR
J 0
(-350 475);
DISPLAY 0.723404 (-350 475);
PAINT SKYBLUE (-350 475);
FORCEPROP 2 LAST PART_TYPE SMLF
J 0
(-350 525);
DISPLAY 1.021277 (-350 525);
FORCEPROP 2 LAST ROOM USB2 BOM2
J 0
(-350 575);
DISPLAY 0.680851 (-350 575);
PAINT RED (-350 575);
FORCEPROP 2 LAST CDS_LIB pure_quanta
J 0
(-125 100);
DISPLAY INVISIBLE (-125 100);
FORCEPROP 1 LAST CDS_LMAN_SYM_OUTLINE -225,175,225,-175
J 0
(-125 100);
DISPLAY 0.468085 (-125 100);
PAINT GREEN (-125 100);
DISPLAY INVISIBLE (-125 100);
FORCEPROP 1 LAST NEEDS_NO_SIZE TRUE
J 0
(100 -18);
DISPLAY 0.723404 (100 -18);
PAINT GREEN (100 -18);
DISPLAY INVISIBLE (100 -18);
FORCEPROP 1 LAST PATH I84
J 0
(100 -75);
DISPLAY 0.723404 (100 -75);
PAINT GREEN (100 -75);
DISPLAY INVISIBLE (100 -75);
FORCEPROP 1 LAST PART_NUMBER AL000211007
J 0
(-352 348);
DISPLAY 0.723404 (-352 348);
PAINT WHITE (-352 348);
DISPLAY INVISIBLE (-352 348);
FORCEADD UNIVERSAL_GND..1
(1475 -425);
FORCEPROP 3 LASTPIN (1475 -375) SIG_NAME GND\g
J 0
(1485 -365);
DISPLAY 0.659574 (1485 -365);
PAINT MONO (1485 -365);
DISPLAY INVISIBLE (1485 -365);
FORCEPROP 2 LAST CDS_LIB pure_quanta_power
J 0
(1475 -425);
DISPLAY INVISIBLE (1475 -425);
FORCEPROP 1 LAST HDL_POWER GND
J 1
(1500 -500);
DISPLAY 0.872340 (1500 -500);
PAINT GREEN (1500 -500);
DISPLAY INVISIBLE (1500 -500);
FORCEPROP 1 LAST PATH I85
J 0
(1550 -425);
DISPLAY 0.872340 (1550 -425);
PAINT AQUA (1550 -425);
DISPLAY INVISIBLE (1550 -425);
FORCEADD UNIVERSAL_GND..1
(1375 -150);
FORCEPROP 3 LASTPIN (1375 -100) SIG_NAME GND\g
J 0
(1385 -90);
DISPLAY 0.659574 (1385 -90);
PAINT MONO (1385 -90);
DISPLAY INVISIBLE (1385 -90);
FORCEPROP 2 LAST CDS_LIB pure_quanta_power
J 0
(1375 -150);
DISPLAY INVISIBLE (1375 -150);
FORCEPROP 1 LAST HDL_POWER GND
J 1
(1400 -225);
DISPLAY 0.872340 (1400 -225);
PAINT GREEN (1400 -225);
DISPLAY INVISIBLE (1400 -225);
FORCEPROP 1 LAST PATH I86
J 0
(1450 -150);
DISPLAY 0.872340 (1450 -150);
PAINT AQUA (1450 -150);
DISPLAY INVISIBLE (1450 -150);
FORCEADD Q_CAP..1
(1475 -200);
FORCEPROP 1 LAST LOCATION C5236
J 0
(1525 -100);
DISPLAY 0.723404 (1525 -100);
FORCEPROP 2 LAST $SEC 1
J 0
(1525 0);
DISPLAY 0.680851 (1525 0);
PAINT MONO (1525 0);
DISPLAY INVISIBLE (1525 0);
FORCEPROP 0 LAST CDS_SEC 1
J 0
(1525 -50);
DISPLAY INVISIBLE (1525 -50);
FORCEPROP 1 LASTPIN (1475 -100) $PN 1
J 0
(1485 -120);
DISPLAY 0.723404 (1485 -120);
PAINT MONO (1485 -120);
FORCEPROP 1 LASTPIN (1475 -300) $PN 2
J 0
(1485 -320);
DISPLAY 0.723404 (1485 -320);
PAINT MONO (1485 -320);
FORCEPROP 2 LAST ROOM USB2 BOM2
J 0
(1525 -50);
DISPLAY 0.680851 (1525 -50);
PAINT RED (1525 -50);
FORCEPROP 1 LAST VALUE 0.1UF
J 0
(1525 -150);
DISPLAY 0.723404 (1525 -150);
FORCEPROP 1 LAST VOLTAGE 25V
J 0
(1525 -200);
DISPLAY 0.723404 (1525 -200);
FORCEPROP 1 LAST PACK_TYPE C0402
J 0
(1525 -400);
DISPLAY 0.723404 (1525 -400);
FORCEPROP 1 LAST MATERIAL EMPTY
J 0
(1525 -300);
DISPLAY 0.723404 (1525 -300);
FORCEPROP 1 LAST TOLERANCE 10%
J 0
(1525 -250);
DISPLAY 0.723404 (1525 -250);
FORCEPROP 2 LAST CDS_LIB pure_quanta
J 0
(1475 -200);
DISPLAY INVISIBLE (1475 -200);
FORCEPROP 1 LAST PATH I87
J 0
(1525 -50);
DISPLAY 0.978723 (1525 -50);
PAINT WHITE (1525 -50);
DISPLAY INVISIBLE (1525 -50);
FORCEPROP 1 LAST PART_NUMBER CH4104KEB00
J 0
(1525 -350);
DISPLAY 0.723404 (1525 -350);
DISPLAY INVISIBLE (1525 -350);
FORCEADD Q_CAP..1
(75 700);
FORCEPROP 1 LAST LOCATION C5229
J 0
(125 800);
DISPLAY 0.723404 (125 800);
FORCEPROP 2 LAST $SEC 1
J 0
(125 900);
DISPLAY 0.680851 (125 900);
PAINT MONO (125 900);
DISPLAY INVISIBLE (125 900);
FORCEPROP 0 LAST CDS_SEC 1
J 0
(125 900);
DISPLAY 0.680851 (125 900);
PAINT MONO (125 900);
DISPLAY INVISIBLE (125 900);
FORCEPROP 1 LASTPIN (75 800) $PN 1
J 0
(85 780);
DISPLAY 0.723404 (85 780);
PAINT MONO (85 780);
FORCEPROP 1 LASTPIN (75 600) $PN 2
J 0
(85 580);
DISPLAY 0.723404 (85 580);
PAINT MONO (85 580);
FORCEPROP 2 LAST ROOM USB2 BOM2
J 0
(125 850);
DISPLAY 0.680851 (125 850);
PAINT RED (125 850);
FORCEPROP 1 LAST MATERIAL EMPTY
J 0
(125 600);
DISPLAY 0.723404 (125 600);
FORCEPROP 1 LAST PACK_TYPE C0402
J 0
(125 500);
DISPLAY 0.723404 (125 500);
FORCEPROP 1 LAST TOLERANCE 10%
J 0
(125 650);
DISPLAY 0.723404 (125 650);
FORCEPROP 1 LAST VOLTAGE 25V
J 0
(125 700);
DISPLAY 0.723404 (125 700);
FORCEPROP 1 LAST VALUE 1UF
J 0
(125 750);
DISPLAY 0.723404 (125 750);
FORCEPROP 2 LAST CDS_LIB pure_quanta
J 0
(75 700);
DISPLAY INVISIBLE (75 700);
FORCEPROP 1 LAST PATH I88
J 0
(125 850);
DISPLAY 0.978723 (125 850);
PAINT WHITE (125 850);
DISPLAY INVISIBLE (125 850);
FORCEPROP 1 LAST PART_NUMBER CH5104KEB02
J 0
(125 550);
DISPLAY 0.723404 (125 550);
DISPLAY INVISIBLE (125 550);
FORCEADD UNIVERSAL_GND..1
(575 375);
FORCEPROP 3 LASTPIN (575 425) SIG_NAME GND\g
J 0
(585 435);
DISPLAY 0.659574 (585 435);
PAINT MONO (585 435);
DISPLAY INVISIBLE (585 435);
FORCEPROP 2 LAST CDS_LIB pure_quanta_power
J 0
(575 375);
DISPLAY INVISIBLE (575 375);
FORCEPROP 1 LAST HDL_POWER GND
J 1
(600 300);
DISPLAY 0.872340 (600 300);
PAINT GREEN (600 300);
DISPLAY INVISIBLE (600 300);
FORCEPROP 1 LAST PATH I89
J 0
(650 375);
DISPLAY 0.872340 (650 375);
PAINT AQUA (650 375);
DISPLAY INVISIBLE (650 375);
FORCEADD Q_RES..1
(1375 175);
FORCEPROP 1 LAST LOCATION R5236
J 0
(1125 175);
DISPLAY 0.723404 (1125 175);
FORCEPROP 2 LAST $SEC 1
J 0
(1325 375);
DISPLAY 0.680851 (1325 375);
PAINT MONO (1325 375);
DISPLAY INVISIBLE (1325 375);
FORCEPROP 2 LAST CDS_SEC 1
J 0
(1325 375);
DISPLAY 1.021277 (1325 375);
DISPLAY INVISIBLE (1325 375);
FORCEPROP 1 LASTPIN (1275 175) $PN 1
J 0
(1287 187);
DISPLAY 0.723404 (1287 187);
PAINT MONO (1287 187);
FORCEPROP 1 LASTPIN (1475 175) $PN 2
J 0
(1437 187);
DISPLAY 0.723404 (1437 187);
PAINT MONO (1437 187);
FORCEPROP 1 LAST VALUE 0
J 2
(1525 175);
DISPLAY 0.723404 (1525 175);
FORCEPROP 1 LAST PACK_TYPE 0402LF
J 0
(1800 175);
DISPLAY 0.723404 (1800 175);
FORCEPROP 1 LAST MATERIAL CHIP
J 0
(1625 175);
DISPLAY 0.723404 (1625 175);
FORCEPROP 2 LAST CDS_LIB pure_quanta
J 0
(1375 175);
DISPLAY INVISIBLE (1375 175);
FORCEPROP 1 LAST TOLERANCE 5%
J 0
(1175 100);
DISPLAY 0.723404 (1175 100);
PAINT SKYBLUE (1175 100);
DISPLAY INVISIBLE (1175 100);
FORCEPROP 1 LAST WATTAGE 1/16W
J 2
(1450 100);
DISPLAY 0.723404 (1450 100);
PAINT SKYBLUE (1450 100);
DISPLAY INVISIBLE (1450 100);
FORCEPROP 1 LAST PATH I90
J 0
(1325 325);
DISPLAY 0.978723 (1325 325);
PAINT WHITE (1325 325);
DISPLAY INVISIBLE (1325 325);
FORCEPROP 1 LAST PART_NUMBER CS00002JB13
J 0
(1100 50);
DISPLAY 0.723404 (1100 50);
PAINT WHITE (1100 50);
DISPLAY INVISIBLE (1100 50);
FORCEADD Q_RES..1
(1375 225);
FORCEPROP 1 LAST LOCATION R5234
J 0
(1125 225);
DISPLAY 0.723404 (1125 225);
FORCEPROP 2 LAST $SEC 1
J 0
(1325 425);
DISPLAY 0.680851 (1325 425);
PAINT MONO (1325 425);
DISPLAY INVISIBLE (1325 425);
FORCEPROP 2 LAST CDS_SEC 1
J 0
(1325 425);
DISPLAY 1.021277 (1325 425);
DISPLAY INVISIBLE (1325 425);
FORCEPROP 1 LASTPIN (1275 225) $PN 1
J 0
(1287 237);
DISPLAY 0.723404 (1287 237);
PAINT MONO (1287 237);
FORCEPROP 1 LASTPIN (1475 225) $PN 2
J 0
(1437 237);
DISPLAY 0.723404 (1437 237);
PAINT MONO (1437 237);
FORCEPROP 1 LAST PACK_TYPE 0402LF
J 0
(1800 225);
DISPLAY 0.723404 (1800 225);
FORCEPROP 1 LAST MATERIAL CHIP
J 0
(1625 225);
DISPLAY 0.723404 (1625 225);
FORCEPROP 1 LAST VALUE 0
J 2
(1525 225);
DISPLAY 0.723404 (1525 225);
FORCEPROP 2 LAST CDS_LIB pure_quanta
J 0
(1375 225);
DISPLAY INVISIBLE (1375 225);
FORCEPROP 1 LAST TOLERANCE 5%
J 0
(1175 150);
DISPLAY 0.723404 (1175 150);
PAINT SKYBLUE (1175 150);
DISPLAY INVISIBLE (1175 150);
FORCEPROP 1 LAST WATTAGE 1/16W
J 2
(1450 150);
DISPLAY 0.723404 (1450 150);
PAINT SKYBLUE (1450 150);
DISPLAY INVISIBLE (1450 150);
FORCEPROP 1 LAST PATH I91
J 0
(1325 375);
DISPLAY 0.978723 (1325 375);
PAINT WHITE (1325 375);
DISPLAY INVISIBLE (1325 375);
FORCEPROP 1 LAST PART_NUMBER CS00002JB13
J 0
(1100 100);
DISPLAY 0.723404 (1100 100);
PAINT WHITE (1100 100);
DISPLAY INVISIBLE (1100 100);
FORCEADD Q_CAP..1
(575 675);
FORCEPROP 1 LAST LOCATION C5234
J 0
(625 775);
DISPLAY 0.723404 (625 775);
FORCEPROP 2 LAST $SEC 1
J 0
(625 875);
DISPLAY 0.680851 (625 875);
PAINT MONO (625 875);
DISPLAY INVISIBLE (625 875);
FORCEPROP 0 LAST CDS_SEC 1
J 0
(625 825);
DISPLAY INVISIBLE (625 825);
FORCEPROP 1 LASTPIN (575 775) $PN 1
J 0
(585 755);
DISPLAY 0.723404 (585 755);
PAINT MONO (585 755);
FORCEPROP 1 LASTPIN (575 575) $PN 2
J 0
(585 555);
DISPLAY 0.723404 (585 555);
PAINT MONO (585 555);
FORCEPROP 1 LAST PACK_TYPE C0402
J 0
(625 475);
DISPLAY 0.723404 (625 475);
FORCEPROP 1 LAST MATERIAL EMPTY
J 0
(625 575);
DISPLAY 0.723404 (625 575);
FORCEPROP 1 LAST VALUE 0.1UF
J 0
(625 725);
DISPLAY 0.723404 (625 725);
FORCEPROP 2 LAST ROOM USB2 BOM2
J 0
(625 825);
DISPLAY 0.680851 (625 825);
PAINT RED (625 825);
FORCEPROP 1 LAST TOLERANCE 10%
J 0
(625 625);
DISPLAY 0.723404 (625 625);
FORCEPROP 1 LAST VOLTAGE 25V
J 0
(625 675);
DISPLAY 0.723404 (625 675);
FORCEPROP 2 LAST CDS_LIB pure_quanta
J 0
(575 675);
DISPLAY INVISIBLE (575 675);
FORCEPROP 1 LAST PATH I92
J 0
(625 825);
DISPLAY 0.978723 (625 825);
PAINT WHITE (625 825);
DISPLAY INVISIBLE (625 825);
FORCEPROP 1 LAST PART_NUMBER CH4104KEB00
J 0
(625 525);
DISPLAY 0.723404 (625 525);
DISPLAY INVISIBLE (625 525);
FORCEADD OFFPAGE..3
(3100 175);
PAINT AQUA (3100 175);
FORCEPROP 2 LAST $XR0 122 
J 0
(3314 175);
DISPLAY 0.638298 (3314 175);
PAINT MONO (3314 175);
FORCEPROP 2 LAST CDS_LIB standard
J 0
(3100 175);
DISPLAY INVISIBLE (3100 175);
FORCEPROP 1 LAST OFFPAGE TRUE
J 0
(3425 50);
DISPLAY 0.872340 (3425 50);
PAINT AQUA (3425 50);
DISPLAY INVISIBLE (3425 50);
FORCEPROP 1 LAST COMMENT_BODY TRUE
J 0
(3050 75);
DISPLAY 0.872340 (3050 75);
PAINT GREEN (3050 75);
DISPLAY INVISIBLE (3050 75);
FORCEPROP 2 LAST PATH I93
J 0
(3325 225);
DISPLAY 1.021277 (3325 225);
DISPLAY INVISIBLE (3325 225);
FORCEADD OFFPAGE..3
(3100 225);
PAINT AQUA (3100 225);
FORCEPROP 2 LAST $XR0 122 
J 0
(3314 225);
DISPLAY 0.638298 (3314 225);
PAINT MONO (3314 225);
FORCEPROP 2 LAST CDS_LIB standard
J 0
(3100 225);
DISPLAY INVISIBLE (3100 225);
FORCEPROP 1 LAST OFFPAGE TRUE
J 0
(3425 100);
DISPLAY 0.872340 (3425 100);
PAINT AQUA (3425 100);
DISPLAY INVISIBLE (3425 100);
FORCEPROP 1 LAST COMMENT_BODY TRUE
J 0
(3050 125);
DISPLAY 0.872340 (3050 125);
PAINT GREEN (3050 125);
DISPLAY INVISIBLE (3050 125);
FORCEPROP 2 LAST PATH I94
J 0
(3325 275);
DISPLAY 1.021277 (3325 275);
DISPLAY INVISIBLE (3325 275);
FORCEADD UNIVERSAL_POWER..1
R 2
(1125 1050);
FORCEPROP 3 LASTPIN (1125 1000) SIG_NAME P3V3_AUX\g
J 0
(1135 1010);
DISPLAY 0.659574 (1135 1010);
PAINT MONO (1135 1010);
DISPLAY INVISIBLE (1135 1010);
FORCEPROP 1 LAST HDL_POWER P3V3_AUX
J 1
(1125 1100);
DISPLAY 0.723404 (1125 1100);
PAINT GREEN (1125 1100);
FORCEPROP 2 LAST CDS_LIB pure_quanta_power
J 0
(1125 1050);
DISPLAY INVISIBLE (1125 1050);
FORCEPROP 1 LAST PATH I95
J 2
(1075 1075);
DISPLAY 0.872340 (1075 1075);
PAINT AQUA (1075 1075);
DISPLAY INVISIBLE (1075 1075);
FORCEADD Q_RES..2
(2725 3650);
FORCEPROP 1 LAST LOCATION R2790
J 0
(2625 3725);
DISPLAY 0.510638 (2625 3725);
FORCEPROP 2 LAST $SEC 1
J 0
(2775 3875);
DISPLAY 0.680851 (2775 3875);
PAINT MONO (2775 3875);
DISPLAY INVISIBLE (2775 3875);
FORCEPROP 2 LAST CDS_SEC 1
J 0
(2775 3875);
DISPLAY 1.021277 (2775 3875);
DISPLAY INVISIBLE (2775 3875);
FORCEPROP 1 LASTPIN (2725 3750) $PN 1
J 0
(2730 3712);
DISPLAY 0.787234 (2730 3712);
PAINT MONO (2730 3712);
FORCEPROP 1 LASTPIN (2725 3550) $PN 2
J 0
(2730 3560);
DISPLAY 0.787234 (2730 3560);
PAINT MONO (2730 3560);
FORCEPROP 1 LAST VALUE 0
J 0
(2675 3675);
DISPLAY 0.510638 (2675 3675);
FORCEPROP 1 LAST MATERIAL EMPTY
J 0
(2600 3525);
DISPLAY 0.510638 (2600 3525);
PAINT RED (2600 3525);
FORCEPROP 2 LAST ROOM USB2 BOM2
J 0
(2425 3575);
DISPLAY 0.680851 (2425 3575);
PAINT RED (2425 3575);
FORCEPROP 1 LAST WATTAGE 1/16W
J 0
(2745 3700);
DISPLAY 0.510638 (2745 3700);
DISPLAY INVISIBLE (2745 3700);
FORCEPROP 1 LAST TOLERANCE 5%
J 0
(2750 3750);
DISPLAY 0.510638 (2750 3750);
DISPLAY INVISIBLE (2750 3750);
FORCEPROP 1 LAST PACK_TYPE 0402LF
J 0
(2745 3550);
DISPLAY 0.510638 (2745 3550);
DISPLAY INVISIBLE (2745 3550);
FORCEPROP 2 LAST CDS_LIB pure_quanta
J 0
(2725 3650);
DISPLAY INVISIBLE (2725 3650);
FORCEPROP 1 LAST PATH I96
J 0
(2775 3825);
DISPLAY 0.978723 (2775 3825);
PAINT WHITE (2775 3825);
DISPLAY INVISIBLE (2775 3825);
FORCEPROP 1 LAST PART_NUMBER CS00002JB13
J 0
(2745 3600);
DISPLAY 0.510638 (2745 3600);
DISPLAY INVISIBLE (2745 3600);
FORCEADD Q_RES..2
(2825 3650);
FORCEPROP 1 LAST LOCATION R2791
J 0
(2880 3725);
DISPLAY 0.510638 (2880 3725);
FORCEPROP 2 LAST $SEC 1
J 0
(2875 3900);
DISPLAY 0.680851 (2875 3900);
PAINT MONO (2875 3900);
DISPLAY INVISIBLE (2875 3900);
FORCEPROP 2 LAST CDS_SEC 1
J 0
(2875 3900);
DISPLAY 1.021277 (2875 3900);
DISPLAY INVISIBLE (2875 3900);
FORCEPROP 1 LASTPIN (2825 3750) $PN 1
J 0
(2830 3712);
DISPLAY 0.787234 (2830 3712);
PAINT MONO (2830 3712);
FORCEPROP 1 LASTPIN (2825 3550) $PN 2
J 0
(2830 3560);
DISPLAY 0.787234 (2830 3560);
PAINT MONO (2830 3560);
FORCEPROP 2 LAST ROOM USB2 BOM2
J 0
(2875 3750);
DISPLAY 0.680851 (2875 3750);
PAINT RED (2875 3750);
FORCEPROP 1 LAST VALUE 0
J 0
(2880 3675);
DISPLAY 0.510638 (2880 3675);
FORCEPROP 1 LAST WATTAGE 1/16W
J 0
(2875 3575);
DISPLAY 0.510638 (2875 3575);
FORCEPROP 1 LAST TOLERANCE 5%
J 0
(2880 3625);
DISPLAY 0.510638 (2880 3625);
FORCEPROP 1 LAST MATERIAL EMPTY
J 0
(2875 3525);
DISPLAY 0.510638 (2875 3525);
PAINT RED (2875 3525);
FORCEPROP 1 LAST PACK_TYPE 0402LF
J 0
(2875 3425);
DISPLAY 0.510638 (2875 3425);
FORCEPROP 2 LAST CDS_LIB pure_quanta
J 0
(2825 3650);
DISPLAY INVISIBLE (2825 3650);
FORCEPROP 1 LAST PATH I97
J 0
(2875 3825);
DISPLAY 0.978723 (2875 3825);
PAINT WHITE (2875 3825);
DISPLAY INVISIBLE (2875 3825);
FORCEPROP 1 LAST PART_NUMBER CS00002JB13
J 0
(2875 3475);
DISPLAY 0.510638 (2875 3475);
DISPLAY INVISIBLE (2875 3475);
FORCEADD Q_RES..2
(-1950 375);
FORCEPROP 1 LAST LOCATION R2789
J 0
(-1925 375);
DISPLAY 0.510638 (-1925 375);
FORCEPROP 2 LAST $SEC 1
J 0
(-1900 600);
DISPLAY 0.680851 (-1900 600);
PAINT MONO (-1900 600);
DISPLAY INVISIBLE (-1900 600);
FORCEPROP 2 LAST CDS_SEC 1
J 0
(-1900 600);
DISPLAY 1.021277 (-1900 600);
DISPLAY INVISIBLE (-1900 600);
FORCEPROP 1 LASTPIN (-1950 475) $PN 1
J 0
(-1945 437);
DISPLAY 0.787234 (-1945 437);
PAINT MONO (-1945 437);
FORCEPROP 1 LASTPIN (-1950 275) $PN 2
J 0
(-1960 285);
DISPLAY 0.787234 (-1960 285);
PAINT MONO (-1960 285);
FORCEPROP 1 LAST MATERIAL EMPTY
J 0
(-1925 325);
DISPLAY 0.510638 (-1925 325);
PAINT RED (-1925 325);
FORCEPROP 2 LAST ROOM USB2 BOM2
J 0
(-1925 575);
DISPLAY 0.680851 (-1925 575);
PAINT RED (-1925 575);
FORCEPROP 1 LAST VALUE 0
J 0
(-1925 425);
DISPLAY 0.510638 (-1925 425);
FORCEPROP 2 LAST CDS_LIB pure_quanta
J 0
(-1950 375);
DISPLAY INVISIBLE (-1950 375);
FORCEPROP 1 LAST PACK_TYPE 0402LF
J 0
(-1930 275);
DISPLAY 0.510638 (-1930 275);
DISPLAY INVISIBLE (-1930 275);
FORCEPROP 1 LAST TOLERANCE 5%
J 0
(-1925 475);
DISPLAY 0.510638 (-1925 475);
DISPLAY INVISIBLE (-1925 475);
FORCEPROP 1 LAST WATTAGE 1/16W
J 0
(-1930 425);
DISPLAY 0.510638 (-1930 425);
DISPLAY INVISIBLE (-1930 425);
FORCEPROP 1 LAST PATH I98
J 0
(-1900 550);
DISPLAY 0.978723 (-1900 550);
PAINT WHITE (-1900 550);
DISPLAY INVISIBLE (-1900 550);
FORCEPROP 1 LAST PART_NUMBER CS00002JB13
J 0
(-1930 325);
DISPLAY 0.510638 (-1930 325);
DISPLAY INVISIBLE (-1930 325);
FORCEADD Q_RES..2
(-2025 375);
FORCEPROP 1 LAST LOCATION R2788
J 0
(-2175 600);
DISPLAY 0.638298 (-2175 600);
FORCEPROP 2 LAST $SEC 1
J 0
(-1975 600);
DISPLAY 0.680851 (-1975 600);
PAINT MONO (-1975 600);
DISPLAY INVISIBLE (-1975 600);
FORCEPROP 2 LAST CDS_SEC 1
J 0
(-1975 600);
DISPLAY 1.021277 (-1975 600);
DISPLAY INVISIBLE (-1975 600);
FORCEPROP 1 LASTPIN (-2025 475) $PN 1
J 0
(-2020 437);
DISPLAY 0.787234 (-2020 437);
PAINT MONO (-2020 437);
FORCEPROP 1 LASTPIN (-2025 275) $PN 2
J 0
(-2020 285);
DISPLAY 0.787234 (-2020 285);
PAINT MONO (-2020 285);
FORCEPROP 1 LAST MATERIAL EMPTY
J 0
(-2200 400);
DISPLAY 0.638298 (-2200 400);
PAINT RED (-2200 400);
FORCEPROP 2 LAST ROOM USB2 BOM2
J 0
(-2350 650);
DISPLAY 0.680851 (-2350 650);
PAINT RED (-2350 650);
FORCEPROP 1 LAST PACK_TYPE 0402LF
J 0
(-2225 300);
DISPLAY 0.638298 (-2225 300);
FORCEPROP 1 LAST VALUE 0
J 0
(-2100 550);
DISPLAY 0.638298 (-2100 550);
FORCEPROP 1 LAST TOLERANCE 5%
J 0
(-2125 500);
DISPLAY 0.638298 (-2125 500);
FORCEPROP 1 LAST WATTAGE 1/16W
J 0
(-2225 450);
DISPLAY 0.638298 (-2225 450);
FORCEPROP 2 LAST CDS_LIB pure_quanta
J 0
(-2025 375);
DISPLAY INVISIBLE (-2025 375);
FORCEPROP 1 LAST PATH I99
J 0
(-1975 550);
DISPLAY 0.978723 (-1975 550);
PAINT WHITE (-1975 550);
DISPLAY INVISIBLE (-1975 550);
FORCEPROP 1 LAST PART_NUMBER CS00002JB13
J 0
(-2400 350);
DISPLAY 0.638298 (-2400 350);
DISPLAY INVISIBLE (-2400 350);
FORCEADD DNS..1
(-1525 2125);
PAINT RED (-1525 2125);
FORCEPROP 2 LAST CDS_LIB mstr_misc
J 0
(-1525 2125);
DISPLAY INVISIBLE (-1525 2125);
FORCEPROP 1 LAST COMMENT_BODY TRUE
R 1
J 0
(-1450 1900);
DISPLAY 0.872340 (-1450 1900);
PAINT GREEN (-1450 1900);
DISPLAY INVISIBLE (-1450 1900);
FORCEADD DNS..1
(-1525 1875);
PAINT RED (-1525 1875);
FORCEPROP 2 LAST CDS_LIB mstr_misc
J 0
(-1525 1875);
DISPLAY INVISIBLE (-1525 1875);
FORCEPROP 1 LAST COMMENT_BODY TRUE
R 1
J 0
(-1450 1650);
DISPLAY 0.872340 (-1450 1650);
PAINT GREEN (-1450 1650);
DISPLAY INVISIBLE (-1450 1650);
FORCEADD DNS..1
(-1525 2000);
PAINT RED (-1525 2000);
FORCEPROP 2 LAST CDS_LIB mstr_misc
J 0
(-1525 2000);
DISPLAY INVISIBLE (-1525 2000);
FORCEPROP 1 LAST COMMENT_BODY TRUE
R 1
J 0
(-1450 1775);
DISPLAY 0.872340 (-1450 1775);
PAINT GREEN (-1450 1775);
DISPLAY INVISIBLE (-1450 1775);
FORCEADD QUANTA_TITLE_BLOCK_C..1
(4825 -925);
FORCEPROP 0 LAST CDS_CON_LAST_MODIFIED Thu Sep 14 16:12:30 2023
J 0
(2940 -910);
DISPLAY INVISIBLE (2940 -910);
FORCEPROP 1 LAST CUSTOM_TXT_CDS <CON_LAST_MODIFIED>
J 0
(2940 -910);
DISPLAY 0.978723 (2940 -910);
FORCEPROP 2 LAST CUSTOM_TXT_CDS <XR_PAGE_TITLE>
J 0
(-3065 4325);
DISPLAY 0.638298 (-3065 4325);
PAINT PINK (-3065 4325);
DISPLAY INVISIBLE (-3065 4325);
FORCEPROP 1 LAST CUSTOM_TXT_CDS <NAME_2>
J 0
(1650 -875);
FORCEPROP 1 LAST CUSTOM_TXT_CDS <NAME_1>
J 0
(1650 -750);
FORCEPROP 1 LAST CUSTOM_TXT_CDS <Q_NUMBER>
J 0
(3422 -822);
DISPLAY 1.212766 (3422 -822);
FORCEPROP 1 LAST CUSTOM_TXT_CDS <Q_PROJ>
J 0
(2443 -823);
DISPLAY 1.212766 (2443 -823);
FORCEPROP 1 LAST CUSTOM_TXT_CDS <Q_REV>
J 0
(4641 -822);
DISPLAY 1.212766 (4641 -822);
FORCEPROP 1 LAST CUSTOM_TXT_CDS <CON_PAGE_NUM> OF <CON_TOTAL_PAGES>
J 0
(4379 -907);
DISPLAY 0.978723 (4379 -907);
FORCEPROP 1 LAST Q_TITLE USB HUB (BMC TO EXAMAX)
J 0
(-4475 -875);
DISPLAY 2.446809 (-4475 -875);
PAINT GREEN (-4475 -875);
FORCEPROP 2 LAST PAGE_BORDER TRUE
J 0
(-3065 4325);
DISPLAY 0.638298 (-3065 4325);
PAINT PINK (-3065 4325);
DISPLAY INVISIBLE (-3065 4325);
FORCEPROP 1 LAST CDS_LMAN_SYM_OUTLINE -9475,6775,100,-125
J 0
(4825 -925);
DISPLAY 0.468085 (4825 -925);
PAINT GREEN (4825 -925);
DISPLAY INVISIBLE (4825 -925);
FORCEPROP 2 LAST CDS_LIB pure_quanta
J 0
(4825 -925);
DISPLAY INVISIBLE (4825 -925);
FORCEPROP 2 LAST CDS_XR_PAGE_TITLE CR-235 : @T6G_MB_LIB.T6G(SCH_1):PAGE235
J 0
(-3065 4325);
DISPLAY 0.638298 (-3065 4325);
PAINT PINK (-3065 4325);
DISPLAY INVISIBLE (-3065 4325);
FORCEPROP 1 LAST Q_DEPT BU9
J 1
(1062 -876);
DISPLAY 1.957447 (1062 -876);
PAINT GREEN (1062 -876);
DISPLAY INVISIBLE (1062 -876);
FORCEPROP 1 LAST COMMENT_BODY TRUE
J 0
(4837 -938);
DISPLAY 0.978723 (4837 -938);
PAINT GREEN (4837 -938);
DISPLAY INVISIBLE (4837 -938);
FORCEADD DNS..2
(3450 3650);
PAINT RED (3450 3650);
FORCEPROP 2 LAST CDS_LIB mstr_misc
J 0
(3450 3650);
DISPLAY INVISIBLE (3450 3650);
FORCEPROP 1 LAST COMMENT_BODY TRUE
R 1
J 0
(3525 3425);
DISPLAY 0.872340 (3525 3425);
PAINT GREEN (3525 3425);
DISPLAY INVISIBLE (3525 3425);
FORCEADD DNS..1
R 1
(-675 -275);
PAINT RED (-675 -275);
FORCEPROP 2 LAST CDS_LIB mstr_misc
J 0
(-675 -275);
DISPLAY INVISIBLE (-675 -275);
FORCEPROP 1 LAST COMMENT_BODY TRUE
R 2
J 0
(-450 -200);
DISPLAY 0.872340 (-450 -200);
PAINT GREEN (-450 -200);
DISPLAY INVISIBLE (-450 -200);
FORCEADD CAD_NOTE..1
(-1750 900);
FORCEPROP 0 LAST S1 R2788/R2786,R2789/R2787 CO-LAYOUT
J 0
(-1875 775);
DISPLAY 0.808511 (-1875 775);
PAINT WHITE (-1875 775);
FORCEPROP 2 LAST CDS_LIB pure_quanta_power
J 0
(-1750 900);
DISPLAY INVISIBLE (-1750 900);
FORCEPROP 1 LAST COMMENT_BODY TRUE
J 0
(-1725 1000);
DISPLAY 0.978723 (-1725 1000);
DISPLAY INVISIBLE (-1725 1000);
FORCEADD CAD_NOTE..1
(1550 475);
FORCEPROP 0 LAST S1 SHORT THE NET USB2_HUB_SWB_R_DP/DN TO USB2_HUB_BUF_SWB_R_DP/DN
J 0
(1425 350);
DISPLAY 0.808511 (1425 350);
PAINT WHITE (1425 350);
FORCEPROP 2 LAST CDS_LIB pure_quanta_power
J 0
(1550 475);
DISPLAY INVISIBLE (1550 475);
FORCEPROP 1 LAST COMMENT_BODY TRUE
J 0
(1575 575);
DISPLAY 0.978723 (1575 575);
DISPLAY INVISIBLE (1575 575);
FORCEADD CAD_NOTE..1
(3375 3325);
FORCEPROP 0 LAST S1 R2790/R3651,R3652/R2791 CO-LAYOUT
J 0
(3250 3200);
DISPLAY 0.808511 (3250 3200);
PAINT WHITE (3250 3200);
FORCEPROP 2 LAST CDS_LIB pure_quanta_power
J 0
(3375 3325);
DISPLAY INVISIBLE (3375 3325);
FORCEPROP 1 LAST COMMENT_BODY TRUE
J 0
(3400 3425);
DISPLAY 0.978723 (3400 3425);
DISPLAY INVISIBLE (3400 3425);
FORCEADD DNS..2
(2775 3650);
PAINT RED (2775 3650);
FORCEPROP 2 LAST CDS_LIB mstr_misc
J 0
(2775 3650);
DISPLAY INVISIBLE (2775 3650);
FORCEPROP 1 LAST COMMENT_BODY TRUE
R 1
J 0
(2850 3425);
DISPLAY 0.872340 (2850 3425);
PAINT GREEN (2850 3425);
DISPLAY INVISIBLE (2850 3425);
FORCEADD DNS..2
(-2275 1000);
PAINT RED (-2275 1000);
FORCEPROP 2 LAST CDS_LIB mstr_misc
J 0
(-2275 1000);
DISPLAY INVISIBLE (-2275 1000);
FORCEPROP 1 LAST COMMENT_BODY TRUE
R 1
J 0
(-2200 775);
DISPLAY 0.872340 (-2200 775);
PAINT GREEN (-2200 775);
DISPLAY INVISIBLE (-2200 775);
FORCEADD DNS..1
R 1
(600 725);
PAINT RED (600 725);
FORCEPROP 2 LAST CDS_LIB mstr_misc
J 0
(600 725);
DISPLAY INVISIBLE (600 725);
FORCEPROP 1 LAST COMMENT_BODY TRUE
R 2
J 0
(825 800);
DISPLAY 0.872340 (825 800);
PAINT GREEN (825 800);
DISPLAY INVISIBLE (825 800);
FORCEADD DNS..1
(-1900 3075);
PAINT RED (-1900 3075);
FORCEPROP 2 LAST CDS_LIB mstr_misc
J 0
(-1900 3075);
DISPLAY INVISIBLE (-1900 3075);
FORCEPROP 1 LAST COMMENT_BODY TRUE
R 1
J 0
(-1825 2850);
DISPLAY 0.872340 (-1825 2850);
PAINT GREEN (-1825 2850);
DISPLAY INVISIBLE (-1825 2850);
FORCEADD DNS..1
(-4125 2350);
PAINT RED (-4125 2350);
FORCEPROP 2 LAST CDS_LIB mstr_misc
J 0
(-4125 2350);
DISPLAY INVISIBLE (-4125 2350);
FORCEPROP 1 LAST COMMENT_BODY TRUE
R 1
J 0
(-4050 2125);
DISPLAY 0.872340 (-4050 2125);
PAINT GREEN (-4050 2125);
DISPLAY INVISIBLE (-4050 2125);
FORCEADD DNS..2
(-2450 1000);
PAINT RED (-2450 1000);
FORCEPROP 2 LAST CDS_LIB mstr_misc
J 0
(-2450 1000);
DISPLAY INVISIBLE (-2450 1000);
FORCEPROP 1 LAST COMMENT_BODY TRUE
R 1
J 0
(-2375 775);
DISPLAY 0.872340 (-2375 775);
PAINT GREEN (-2375 775);
DISPLAY INVISIBLE (-2375 775);
FORCEADD DNS..1
R 1
(-1150 -250);
PAINT RED (-1150 -250);
FORCEPROP 2 LAST CDS_LIB mstr_misc
J 0
(-1150 -250);
DISPLAY INVISIBLE (-1150 -250);
FORCEPROP 1 LAST COMMENT_BODY TRUE
R 2
J 0
(-925 -175);
DISPLAY 0.872340 (-925 -175);
PAINT GREEN (-925 -175);
DISPLAY INVISIBLE (-925 -175);
FORCEADD DNS..1
R 1
(1500 -200);
PAINT RED (1500 -200);
FORCEPROP 2 LAST CDS_LIB mstr_misc
J 0
(1500 -200);
DISPLAY INVISIBLE (1500 -200);
FORCEPROP 1 LAST COMMENT_BODY TRUE
R 2
J 0
(1725 -125);
DISPLAY 0.872340 (1725 -125);
PAINT GREEN (1725 -125);
DISPLAY INVISIBLE (1725 -125);
FORCEADD DNS..2
(3625 3650);
PAINT RED (3625 3650);
FORCEPROP 2 LAST CDS_LIB mstr_misc
J 0
(3625 3650);
DISPLAY INVISIBLE (3625 3650);
FORCEPROP 1 LAST COMMENT_BODY TRUE
R 1
J 0
(3700 3425);
DISPLAY 0.872340 (3700 3425);
PAINT GREEN (3700 3425);
DISPLAY INVISIBLE (3700 3425);
FORCEADD DNS..1
R 1
(-125 75);
PAINT RED (-125 75);
FORCEPROP 2 LAST CDS_LIB mstr_misc
J 0
(-125 75);
DISPLAY INVISIBLE (-125 75);
FORCEPROP 1 LAST COMMENT_BODY TRUE
R 2
J 0
(100 150);
DISPLAY 0.872340 (100 150);
PAINT GREEN (100 150);
DISPLAY INVISIBLE (100 150);
FORCEADD DNS..2
(-1975 375);
PAINT RED (-1975 375);
FORCEPROP 2 LAST CDS_LIB mstr_misc
J 0
(-1975 375);
DISPLAY INVISIBLE (-1975 375);
FORCEPROP 1 LAST COMMENT_BODY TRUE
R 1
J 0
(-1900 150);
DISPLAY 0.872340 (-1900 150);
PAINT GREEN (-1900 150);
DISPLAY INVISIBLE (-1900 150);
FORCEADD DNS..1
(-1525 2275);
PAINT RED (-1525 2275);
FORCEPROP 2 LAST CDS_LIB mstr_misc
J 0
(-1525 2275);
DISPLAY INVISIBLE (-1525 2275);
FORCEPROP 1 LAST COMMENT_BODY TRUE
R 1
J 0
(-1450 2050);
DISPLAY 0.872340 (-1450 2050);
PAINT GREEN (-1450 2050);
DISPLAY INVISIBLE (-1450 2050);
FORCEADD DNS..1
R 1
(100 750);
PAINT RED (100 750);
FORCEPROP 2 LAST CDS_LIB mstr_misc
J 0
(100 750);
DISPLAY INVISIBLE (100 750);
FORCEPROP 1 LAST COMMENT_BODY TRUE
R 2
J 0
(325 825);
DISPLAY 0.872340 (325 825);
PAINT GREEN (325 825);
DISPLAY INVISIBLE (325 825);
WIRE 16 -1 (3750 4425)(3700 4425);
WIRE 16 -1 (3700 4425)(3700 4375);
WIRE 16 -1 (4300 4425)(4350 4425);
WIRE 16 -1 (4350 4425)(4350 4375);
WIRE 16 -1 (4475 4275)(4475 4200);
WIRE 16 -1 (3475 4275)(3475 4200);
WIRE 16 -1 (1475 4275)(1975 4275);
WIRE 16 -1 (-1075 3000)(-1075 2875);
WIRE 16 -1 (-1900 4025)(-1900 3875);
WIRE 16 -1 (600 3325)(725 3325);
WIRE 16 -1 (725 3325)(725 3175);
WIRE 16 -1 (-750 2975)(-750 2850);
WIRE 16 -1 (-4150 3350)(-4150 3050);
WIRE 16 -1 (-4150 1975)(-4150 2250);
WIRE 16 -1 (3625 3500)(3625 3575);
WIRE 16 -1 (3450 3500)(3450 3575);
WIRE 16 -1 (-2275 850)(-2275 925);
WIRE 16 -1 (-2450 850)(-2450 925);
WIRE 16 -1 (-1150 -325)(-1150 -400);
WIRE 16 -1 (-675 -350)(-675 -400);
WIRE 16 -1 (1475 -300)(1475 -375);
WIRE 16 -1 (-2825 3425)(-3475 3425);
FORCEPROP 2 LAST SIG_NAME RST_USB_HUB_N
J 0
(-3460 3435);
DISPLAY 0.723404 (-3460 3435);
PAINT WHITE (-3460 3435);
WIRE 16 -1 (-2275 3250)(-2275 3375);
WIRE 16 -1 (-2275 3375)(-1900 3375);
WIRE 16 -1 (-1900 3375)(-1900 3425);
WIRE 16 -1 (-1900 3375)(-1900 3200);
WIRE 16 -1 (-350 3425)(-1900 3425);
WIRE 16 -1 (-1900 3425)(-1900 3675);
WIRE 16 -1 (-2625 3425)(-1900 3425);
FORCEPROP 2 LAST SIG_NAME RST_USB_HUB_R_N
J 0
(-2485 3435);
DISPLAY 0.723404 (-2485 3435);
PAINT WHITE (-2485 3435);
FORCEPROP 2 LASTPROP $XRERR UNIQUE?
J 0
(-2725 3435);
DISPLAY 0.638298 (-2725 3435);
PAINT MONO (-2725 3435);
DISPLAY INVISIBLE (-2725 3435);
WIRE 16 -1 (-4150 2450)(-4150 2625);
WIRE 16 -1 (-3075 2625)(-4150 2625);
FORCEPROP 2 LAST SIG_NAME USB_HUB_PSELF
J 0
(-3810 2635);
DISPLAY 0.808511 (-3810 2635);
PAINT WHITE (-3810 2635);
WIRE 16 -1 (-4150 2850)(-4150 2625);
WIRE 16 -1 (-825 4400)(-825 4225);
WIRE 16 -1 (-825 4225)(-1175 4225);
WIRE 16 -1 (-1175 4400)(-1175 4225);
WIRE 16 -1 (-1175 4225)(-1550 4225);
WIRE 16 -1 (-1550 4400)(-1550 4225);
WIRE 16 -1 (-1550 4225)(-1925 4225);
WIRE 16 -1 (-1925 4400)(-1925 4225);
WIRE 16 -1 (-2300 4225)(-1925 4225);
WIRE 16 -1 (-2300 4400)(-2300 4225);
WIRE 16 -1 (-2675 4225)(-2300 4225);
WIRE 16 -1 (-2675 4400)(-2675 4225);
WIRE 16 -1 (-3075 4225)(-2675 4225);
WIRE 16 -1 (-3075 4400)(-3075 4225);
WIRE 16 -1 (-3450 4225)(-3075 4225);
WIRE 16 -1 (-3450 4400)(-3450 4225);
WIRE 16 -1 (-3450 4225)(-3450 4150);
WIRE 16 -1 (-3850 4800)(-4000 4800);
WIRE 16 -1 (-4000 4900)(-4000 4800);
WIRE 16 -1 (-1900 3000)(-1900 2925);
WIRE 16 -1 (-1900 2925)(-2275 2925);
WIRE 16 -1 (-2275 3050)(-2275 2925);
WIRE 16 -1 (-2275 2925)(-2275 2900);
WIRE 16 -1 (-2175 1875)(-1650 1875);
WIRE 16 -1 (-2175 2000)(-2175 1875);
WIRE 16 -1 (-1650 2000)(-2175 2000);
WIRE 16 -1 (-2175 2125)(-2175 2000);
WIRE 16 -1 (-1650 2125)(-2175 2125);
WIRE 16 -1 (-2175 2275)(-2175 2125);
WIRE 16 -1 (-1650 2275)(-2175 2275);
WIRE 16 -1 (-2175 2475)(-2175 2275);
WIRE 16 -1 (250 25)(1375 25);
WIRE 16 -1 (1375 -100)(1375 25);
WIRE 16 -1 (75 600)(75 475);
WIRE 16 -1 (75 475)(575 475);
WIRE 16 -1 (575 575)(575 475);
WIRE 16 -1 (575 475)(575 425);
WIRE 16 -1 (575 900)(1125 900);
WIRE 16 -1 (575 775)(575 900);
WIRE 16 -1 (575 900)(75 900);
WIRE 16 -1 (1125 1000)(1125 900);
WIRE 16 -1 (1125 900)(1125 125);
WIRE 16 -1 (1125 125)(250 125);
WIRE 16 -1 (75 900)(75 800);
WIRE 16 -1 (-350 3325)(-750 3325);
FORCEPROP 2 LAST SIG_NAME USB_HUB_PGANG
J 0
(-785 3335);
DISPLAY 0.510638 (-785 3335);
PAINT WHITE (-785 3335);
FORCEPROP 2 LASTPROP $XRERR UNIQUE?
J 0
(-1025 3335);
DISPLAY 0.638298 (-1025 3335);
PAINT MONO (-1025 3335);
DISPLAY INVISIBLE (-1025 3335);
WIRE 16 -1 (-750 3325)(-750 3175);
WIRE 16 -1 (-350 3375)(-825 3375);
FORCEPROP 2 LAST SIG_NAME USB_HUB_PSELF
J 0
(-785 3385);
DISPLAY 0.510638 (-785 3385);
PAINT WHITE (-785 3385);
WIRE 16 -1 (-350 3475)(-1075 3475);
FORCEPROP 2 LAST SIG_NAME USB_HUB_RREF
J 0
(-910 3485);
DISPLAY 0.808511 (-910 3485);
PAINT WHITE (-910 3485);
FORCEPROP 2 LASTPROP $XRERR UNIQUE?
J 0
(-1150 3485);
DISPLAY 0.638298 (-1150 3485);
PAINT MONO (-1150 3485);
DISPLAY INVISIBLE (-1150 3485);
WIRE 16 -1 (-1075 3475)(-1075 3200);
WIRE 16 -1 (-1125 3925)(-1300 3925);
WIRE 16 -1 (-1300 3925)(-1300 4025);
WIRE 16 -1 (-1300 4025)(-500 4025);
WIRE 16 -1 (-500 4025)(-350 4025);
WIRE 16 -1 (-500 4075)(-500 4025);
WIRE 16 -1 (-500 4125)(-500 4075);
WIRE 16 -1 (-500 4075)(-350 4075);
WIRE 16 -1 (-350 4125)(-500 4125);
WIRE 16 -1 (-500 4125)(-500 4225);
WIRE 16 -1 (-350 4225)(-500 4225);
WIRE 16 -1 (-500 4225)(-500 4325);
WIRE 16 -1 (-500 4325)(-500 4800);
WIRE 16 -1 (-350 4325)(-500 4325);
WIRE 16 -1 (-500 4800)(-825 4800);
WIRE 16 -1 (-825 4600)(-825 4800);
WIRE 16 -1 (-825 4800)(-1175 4800);
WIRE 16 -1 (-1175 4600)(-1175 4800);
WIRE 16 -1 (-1175 4800)(-1550 4800);
WIRE 16 -1 (-1550 4800)(-1925 4800);
WIRE 16 -1 (-1550 4800)(-1550 4600);
WIRE 16 -1 (-1925 4800)(-1925 4600);
WIRE 16 -1 (-1925 4800)(-2300 4800);
WIRE 16 -1 (-2300 4800)(-2300 4600);
WIRE 16 -1 (-2300 4800)(-2675 4800);
WIRE 16 -1 (-2675 4600)(-2675 4800);
WIRE 16 -1 (-2675 4800)(-3075 4800);
WIRE 16 -1 (-3450 4800)(-3075 4800);
WIRE 16 -1 (-3075 4600)(-3075 4800);
WIRE 16 -1 (-3450 4800)(-3450 4600);
WIRE 16 -1 (-3450 4800)(-3650 4800);
FORCEPROP 2 LAST SIG_NAME P3V3_AUX_USB_HUB
J 0
(-3460 4810);
DISPLAY 0.510638 (-3460 4810);
PAINT WHITE (-3460 4810);
FORCEPROP 2 LASTPROP $XRERR UNIQUE?
J 0
(-3700 4810);
DISPLAY 0.638298 (-3700 4810);
PAINT MONO (-3700 4810);
DISPLAY INVISIBLE (-3700 4810);
WIRE 16 -1 (-925 3925)(-350 3925);
FORCEPROP 2 LAST SIG_NAME USB_HUB_DVDD
J 0
(-810 3935);
DISPLAY 0.638298 (-810 3935);
PAINT WHITE (-810 3935);
FORCEPROP 2 LASTPROP $XRERR UNIQUE?
J 0
(-1050 3935);
DISPLAY 0.638298 (-1050 3935);
PAINT MONO (-1050 3935);
DISPLAY INVISIBLE (-1050 3935);
WIRE 16 -1 (-350 3625)(-925 3625);
FORCEPROP 2 LAST SIG_NAME USB_HUB_OVCUR4
J 0
(-910 3635);
DISPLAY 0.723404 (-910 3635);
PAINT WHITE (-910 3635);
WIRE 16 -1 (1625 3775)(600 3775);
FORCEPROP 2 LAST SIG_NAME USB2_HUB_SWB_DN
J 0
(740 3785);
DISPLAY 0.723404 (740 3785);
PAINT WHITE (740 3785);
WIRE 16 -1 (1625 3825)(600 3825);
FORCEPROP 2 LAST SIG_NAME USB2_HUB_SWB_DP
J 0
(740 3835);
DISPLAY 0.723404 (740 3835);
PAINT WHITE (740 3835);
WIRE 16 -1 (600 3875)(2450 3875);
FORCEPROP 2 LAST SIG_NAME USB2_P0_R_DN
J 0
(740 3885);
DISPLAY 0.723404 (740 3885);
PAINT WHITE (740 3885);
FORCEPROP 2 LASTPROP $XRERR UNIQUE?
J 0
(500 3885);
DISPLAY 0.638298 (500 3885);
PAINT MONO (500 3885);
DISPLAY INVISIBLE (500 3885);
WIRE 16 -1 (600 3925)(2450 3925);
FORCEPROP 2 LAST SIG_NAME USB2_P0_R_DP
J 0
(740 3935);
DISPLAY 0.723404 (740 3935);
PAINT WHITE (740 3935);
FORCEPROP 2 LASTPROP $XRERR UNIQUE?
J 0
(500 3935);
DISPLAY 0.638298 (500 3935);
PAINT MONO (500 3935);
DISPLAY INVISIBLE (500 3935);
WIRE 16 -1 (4800 4625)(4475 4625);
WIRE 16 -1 (4800 4075)(4800 4625);
WIRE 16 -1 (4300 4625)(4475 4625);
WIRE 16 -1 (4475 4625)(4475 4475);
WIRE 16 -1 (600 4075)(4800 4075);
FORCEPROP 2 LAST SIG_NAME USB_HUB_XTAL_OUT
J 0
(740 4085);
DISPLAY 0.638298 (740 4085);
PAINT WHITE (740 4085);
FORCEPROP 2 LASTPROP $XRERR UNIQUE?
J 0
(500 4085);
DISPLAY 0.638298 (500 4085);
PAINT MONO (500 4085);
DISPLAY INVISIBLE (500 4085);
WIRE 16 -1 (3750 4625)(3475 4625);
WIRE 16 -1 (3475 4625)(3400 4625);
WIRE 16 -1 (3475 4625)(3475 4475);
WIRE 16 -1 (3400 4625)(3400 4125);
WIRE 16 -1 (600 4125)(3400 4125);
FORCEPROP 2 LAST SIG_NAME USB_HUB_XTAL_IN
J 0
(740 4135);
DISPLAY 0.638298 (740 4135);
PAINT WHITE (740 4135);
FORCEPROP 2 LASTPROP $XRERR UNIQUE?
J 0
(500 4135);
DISPLAY 0.638298 (500 4135);
PAINT MONO (500 4135);
DISPLAY INVISIBLE (500 4135);
WIRE 16 -1 (600 4275)(1275 4275);
FORCEPROP 0 LAST SIG_NAME USB_HUB_TEST
J 0
(690 4285);
DISPLAY 0.723404 (690 4285);
PAINT WHITE (690 4285);
FORCEPROP 2 LASTPROP $XRERR UNIQUE?
J 0
(450 4285);
DISPLAY 0.638298 (450 4285);
PAINT MONO (450 4285);
DISPLAY INVISIBLE (450 4285);
WIRE 16 -1 (3625 3775)(3625 3875);
WIRE 16 -1 (4150 3875)(3625 3875);
WIRE 16 -1 (2825 3875)(3625 3875);
WIRE 16 -1 (2825 3750)(2825 3875);
WIRE 16 -1 (2825 3875)(2650 3875);
FORCEPROP 2 LAST SIG_NAME USB2_HOST_BMC_B_DN
J 0
(2790 3885);
DISPLAY 0.723404 (2790 3885);
PAINT WHITE (2790 3885);
WIRE 16 2175 (2425 3375)(3175 3375);
WIRE 16 2175 (2425 4050)(2425 3375);
WIRE 16 2175 (3175 4050)(3175 3375);
WIRE 16 2175 (2425 4050)(3175 4050);
WIRE 16 -1 (-2275 1125)(-2275 1200);
WIRE 16 -1 (-2275 1200)(-1950 1200);
WIRE 16 -1 (-1950 1325)(-1950 1200);
WIRE 16 -1 (-1950 475)(-1950 1200);
WIRE 16 -1 (2825 1325)(-1950 1325);
FORCEPROP 2 LAST SIG_NAME USB2_HOST_BMC_B_BUF_DN
J 0
(-160 1335);
DISPLAY 0.808511 (-160 1335);
PAINT WHITE (-160 1335);
FORCEPROP 2 LASTPROP $XRERR UNIQUE?
J 0
(-400 1335);
DISPLAY 0.638298 (-400 1335);
PAINT MONO (-400 1335);
DISPLAY INVISIBLE (-400 1335);
WIRE 16 -1 (2825 3550)(2825 1325);
WIRE 16 -1 (-2450 1125)(-2450 1250);
WIRE 16 -1 (-2450 1250)(-2025 1250);
WIRE 16 -1 (-2025 1425)(-2025 1250);
WIRE 16 -1 (-2025 475)(-2025 1250);
WIRE 16 -1 (2725 1425)(-2025 1425);
FORCEPROP 2 LAST SIG_NAME USB2_HOST_BMC_B_BUF_DP
J 0
(-160 1435);
DISPLAY 0.808511 (-160 1435);
PAINT WHITE (-160 1435);
FORCEPROP 2 LASTPROP $XRERR UNIQUE?
J 0
(-400 1435);
DISPLAY 0.638298 (-400 1435);
PAINT MONO (-400 1435);
DISPLAY INVISIBLE (-400 1435);
WIRE 16 -1 (2725 3550)(2725 1425);
WIRE 16 2175 (-2425 725)(-1522 725);
WIRE 16 2175 (-2425 725)(-2425 25);
WIRE 16 2175 (-1522 725)(-1522 25);
WIRE 16 2175 (-2425 25)(-1522 25);
WIRE 16 -1 (-500 225)(-2025 225);
FORCEPROP 2 LAST SIG_NAME USB2_HUB_BUF_SWB_R_DP
J 0
(-1405 225);
DISPLAY 0.808511 (-1405 225);
PAINT WHITE (-1405 225);
FORCEPROP 2 LASTPROP $XR0 235 
J 0
(-1675 225);
DISPLAY 0.638298 (-1675 225);
PAINT MONO (-1675 225);
WIRE 16 -1 (-2025 275)(-2025 225);
WIRE 16 -1 (-2025 225)(-2075 225);
WIRE 16 -1 (-500 175)(-1950 175);
FORCEPROP 2 LAST SIG_NAME USB2_HUB_BUF_SWB_R_DN
J 0
(-1405 175);
DISPLAY 0.808511 (-1405 175);
PAINT WHITE (-1405 175);
FORCEPROP 2 LASTPROP $XR0 235 
J 0
(-1675 175);
DISPLAY 0.638298 (-1675 175);
PAINT MONO (-1675 175);
WIRE 16 -1 (-1950 275)(-1950 175);
WIRE 16 -1 (-1950 175)(-2075 175);
WIRE 16 -1 (-1375 125)(-500 125);
FORCEPROP 2 LAST SIG_NAME TP_USB2_TEST
J 0
(-1060 135);
DISPLAY 0.723404 (-1060 135);
PAINT WHITE (-1060 135);
FORCEPROP 2 LASTPROP $XRERR UNIQUE?
J 0
(-1615 125);
DISPLAY 0.638298 (-1615 125);
PAINT MONO (-1615 125);
DISPLAY INVISIBLE (-1615 125);
WIRE 16 -1 (250 75)(1475 75);
FORCEPROP 2 LAST SIG_NAME PD_U5201_VREG
J 0
(365 85);
DISPLAY 0.723404 (365 85);
PAINT WHITE (365 85);
FORCEPROP 2 LASTPROP $XRERR UNIQUE?
J 0
(125 85);
DISPLAY 0.638298 (125 85);
PAINT MONO (125 85);
DISPLAY INVISIBLE (125 85);
WIRE 16 -1 (1475 75)(1475 -100);
WIRE 16 -1 (250 175)(1275 175);
FORCEPROP 2 LAST SIG_NAME USB2_HUB_BUF_SWB_R_DN
J 0
(365 185);
DISPLAY 0.723404 (365 185);
PAINT WHITE (365 185);
FORCEPROP 2 LASTPROP $XR0 235 
J 0
(149 185);
DISPLAY 0.638298 (149 185);
PAINT MONO (149 185);
WIRE 16 -1 (250 225)(1275 225);
FORCEPROP 2 LAST SIG_NAME USB2_HUB_BUF_SWB_R_DP
J 0
(365 235);
DISPLAY 0.723404 (365 235);
PAINT WHITE (365 235);
FORCEPROP 2 LASTPROP $XR0 235 
J 0
(149 235);
DISPLAY 0.638298 (149 235);
PAINT MONO (149 235);
WIRE 16 -1 (-500 -25)(-675 -25);
FORCEPROP 2 LAST SIG_NAME PD_U5201_EQ
J 0
(-1060 -25);
DISPLAY 0.723404 (-1060 -25);
PAINT WHITE (-1060 -25);
FORCEPROP 2 LASTPROP $XRERR UNIQUE?
J 0
(-1300 -25);
DISPLAY 0.638298 (-1300 -25);
PAINT MONO (-1300 -25);
DISPLAY INVISIBLE (-1300 -25);
WIRE 16 -1 (-675 -25)(-675 -150);
WIRE 16 -1 (3450 3775)(3450 3925);
WIRE 16 -1 (4150 3925)(3450 3925);
WIRE 16 -1 (2725 3925)(3450 3925);
FORCEPROP 2 LAST SIG_NAME USB2_HOST_BMC_B_DP
J 0
(2790 3935);
DISPLAY 0.723404 (2790 3935);
PAINT WHITE (2790 3935);
WIRE 16 -1 (2725 3925)(2650 3925);
WIRE 16 -1 (2725 3750)(2725 3925);
WIRE 16 -1 (-1375 75)(-500 75);
FORCEPROP 2 LAST SIG_NAME TP_USB2_CD
J 0
(-1060 85);
DISPLAY 0.723404 (-1060 85);
PAINT WHITE (-1060 85);
FORCEPROP 2 LASTPROP $XRERR UNIQUE?
J 0
(-1615 75);
DISPLAY 0.638298 (-1615 75);
PAINT MONO (-1615 75);
DISPLAY INVISIBLE (-1615 75);
WIRE 16 -1 (-500 25)(-1150 25);
FORCEPROP 2 LAST SIG_NAME PD_U5201_RSTN
J 0
(-1060 35);
DISPLAY 0.723404 (-1060 35);
PAINT WHITE (-1060 35);
FORCEPROP 2 LASTPROP $XRERR UNIQUE?
J 0
(-1300 35);
DISPLAY 0.638298 (-1300 35);
PAINT MONO (-1300 35);
DISPLAY INVISIBLE (-1300 35);
WIRE 16 -1 (-1150 25)(-1150 -125);
WIRE 16 -1 (250 -25)(1125 -25);
FORCEPROP 2 LAST SIG_NAME TP_USB2_ENA_HS
J 0
(365 -15);
DISPLAY 0.723404 (365 -15);
PAINT WHITE (365 -15);
FORCEPROP 2 LASTPROP $XRERR UNIQUE?
J 0
(1155 -25);
DISPLAY 0.638298 (1155 -25);
PAINT MONO (1155 -25);
DISPLAY INVISIBLE (1155 -25);
WIRE 16 -1 (1475 175)(3050 175);
FORCEPROP 2 LAST SIG_NAME USB2_HUB_BUF_SWB_DN
J 0
(2115 185);
DISPLAY 0.723404 (2115 185);
PAINT WHITE (2115 185);
WIRE 16 -1 (1475 225)(3050 225);
FORCEPROP 2 LAST SIG_NAME USB2_HUB_BUF_SWB_DP
J 0
(2115 235);
DISPLAY 0.723404 (2115 235);
PAINT WHITE (2115 235);
WIRE 16 -1 (-3500 225)(-2275 225);
FORCEPROP 2 LAST SIG_NAME USB2_HUB_SWB_DP
J 0
(-3485 235);
DISPLAY 0.723404 (-3485 235);
PAINT WHITE (-3485 235);
WIRE 16 -1 (600 3475)(1325 3475);
FORCEPROP 0 LAST SIG_NAME NC_USB_HUB_DM4
J 0
(740 3485);
DISPLAY 0.723404 (740 3485);
PAINT WHITE (740 3485);
FORCEPROP 2 LASTPROP $XRERR UNIQUE?
J 0
(1355 3475);
DISPLAY 0.638298 (1355 3475);
PAINT MONO (1355 3475);
DISPLAY INVISIBLE (1355 3475);
WIRE 16 -1 (600 3725)(1325 3725);
FORCEPROP 0 LAST SIG_NAME NC_USB_HUB_DP2
J 0
(740 3735);
DISPLAY 0.723404 (740 3735);
PAINT WHITE (740 3735);
FORCEPROP 2 LASTPROP $XRERR UNIQUE?
J 0
(1355 3725);
DISPLAY 0.638298 (1355 3725);
PAINT MONO (1355 3725);
DISPLAY INVISIBLE (1355 3725);
WIRE 16 -1 (-3500 175)(-2275 175);
FORCEPROP 2 LAST SIG_NAME USB2_HUB_SWB_DN
J 0
(-3485 185);
DISPLAY 0.723404 (-3485 185);
PAINT WHITE (-3485 185);
WIRE 16 -1 (-875 2275)(-1450 2275);
FORCEPROP 2 LAST SIG_NAME USB_HUB_OVCUR1
J 0
(-1435 2285);
DISPLAY 0.723404 (-1435 2285);
PAINT WHITE (-1435 2285);
WIRE 16 -1 (-875 2125)(-1450 2125);
FORCEPROP 2 LAST SIG_NAME USB_HUB_OVCUR2
J 0
(-1435 2135);
DISPLAY 0.723404 (-1435 2135);
PAINT WHITE (-1435 2135);
WIRE 16 -1 (-875 2000)(-1450 2000);
FORCEPROP 2 LAST SIG_NAME USB_HUB_OVCUR3
J 0
(-1435 2010);
DISPLAY 0.723404 (-1435 2010);
PAINT WHITE (-1435 2010);
WIRE 16 -1 (-350 3725)(-925 3725);
FORCEPROP 2 LAST SIG_NAME USB_HUB_OVCUR2
J 0
(-910 3735);
DISPLAY 0.723404 (-910 3735);
PAINT WHITE (-910 3735);
WIRE 16 -1 (-875 1875)(-1450 1875);
FORCEPROP 2 LAST SIG_NAME USB_HUB_OVCUR4
J 0
(-1435 1885);
DISPLAY 0.723404 (-1435 1885);
PAINT WHITE (-1435 1885);
WIRE 16 -1 (-350 3775)(-925 3775);
FORCEPROP 2 LAST SIG_NAME USB_HUB_OVCUR1
J 0
(-910 3785);
DISPLAY 0.723404 (-910 3785);
PAINT WHITE (-910 3785);
WIRE 16 -1 (-350 3675)(-925 3675);
FORCEPROP 2 LAST SIG_NAME USB_HUB_OVCUR3
J 0
(-910 3685);
DISPLAY 0.723404 (-910 3685);
PAINT WHITE (-910 3685);
WIRE 16 -1 (600 3575)(1325 3575);
FORCEPROP 0 LAST SIG_NAME NC_USB_HUB_DM3
J 0
(740 3585);
DISPLAY 0.723404 (740 3585);
PAINT WHITE (740 3585);
FORCEPROP 2 LASTPROP $XRERR UNIQUE?
J 0
(1355 3575);
DISPLAY 0.638298 (1355 3575);
PAINT MONO (1355 3575);
DISPLAY INVISIBLE (1355 3575);
WIRE 16 -1 (600 3525)(1325 3525);
FORCEPROP 0 LAST SIG_NAME NC_USB_HUB_DP4
J 0
(740 3535);
DISPLAY 0.723404 (740 3535);
PAINT WHITE (740 3535);
FORCEPROP 2 LASTPROP $XRERR UNIQUE?
J 0
(1355 3525);
DISPLAY 0.638298 (1355 3525);
PAINT MONO (1355 3525);
DISPLAY INVISIBLE (1355 3525);
WIRE 16 -1 (600 3625)(1325 3625);
FORCEPROP 0 LAST SIG_NAME NC_USB_HUB_DP3
J 0
(740 3635);
DISPLAY 0.723404 (740 3635);
PAINT WHITE (740 3635);
FORCEPROP 2 LASTPROP $XRERR UNIQUE?
J 0
(1355 3625);
DISPLAY 0.638298 (1355 3625);
PAINT MONO (1355 3625);
DISPLAY INVISIBLE (1355 3625);
WIRE 16 -1 (600 3675)(1325 3675);
FORCEPROP 0 LAST SIG_NAME NC_USB_HUB_DM2
J 0
(740 3685);
DISPLAY 0.723404 (740 3685);
PAINT WHITE (740 3685);
FORCEPROP 2 LASTPROP $XRERR UNIQUE?
J 0
(1355 3675);
DISPLAY 0.638298 (1355 3675);
PAINT MONO (1355 3675);
DISPLAY INVISIBLE (1355 3675);
WIRE 16 -1 (600 4325)(1275 4325);
FORCEPROP 0 LAST SIG_NAME NC_USB_HUB_SDA
J 0
(690 4335);
DISPLAY 0.723404 (690 4335);
PAINT WHITE (690 4335);
FORCEPROP 2 LASTPROP $XRERR UNIQUE?
J 0
(1305 4325);
DISPLAY 0.638298 (1305 4325);
PAINT MONO (1305 4325);
DISPLAY INVISIBLE (1305 4325);
DOT 1 (-500 4325);
DOT 1 (575 475);
DOT 1 (-1950 175);
DOT 1 (3625 3875);
DOT 1 (-2025 225);
DOT 1 (-2175 2275);
DOT 1 (-2175 2000);
DOT 1 (-2175 2125);
DOT 1 (-2275 2925);
DOT 1 (-1900 3425);
DOT 1 (-1175 4225);
DOT 1 (-1925 4800);
DOT 1 (-500 4025);
DOT 1 (-2675 4800);
DOT 1 (-3450 4800);
DOT 1 (-3450 4225);
DOT 1 (-3075 4225);
DOT 1 (-3075 4800);
DOT 1 (-2675 4225);
DOT 1 (-2300 4225);
DOT 1 (-2300 4800);
DOT 1 (-1925 4225);
DOT 1 (-825 4800);
DOT 1 (-1550 4225);
DOT 1 (-1550 4800);
DOT 1 (-1175 4800);
DOT 1 (2825 3875);
DOT 1 (3450 3925);
DOT 1 (4475 4625);
DOT 1 (2725 3925);
DOT 1 (3475 4625);
DOT 1 (1125 900);
DOT 1 (-1950 1200);
DOT 1 (-2025 1250);
DOT 1 (-4150 2625);
DOT 1 (-1900 3375);
DOT 1 (-500 4075);
DOT 1 (-500 4225);
DOT 1 (-500 4125);
DOT 1 (575 900);
FORCENOTE
HUB ADDRESS : 0X2C
(-300 2875) 0;
DISPLAY LEFT (-300 2875);
DISPLAY 2.106383 (-300 2875);
PAINT WHITE (-300 2875);
FORCENOTE
USB_HUB_I2C ONLY FOR EEPROM.
(800 4500) 0;
DISPLAY LEFT (800 4500);
DISPLAY 0.808511 (800 4500);
PAINT WHITE (800 4500);
FORCENOTE
$CDS_IMAGE|clipboard_0_7.jpg|1350|1027
(3600 975) 0;
DISPLAY LEFT (3600 975);
QUIT
